FILE_TYPE = MACRO_DRAWING;
SET COLOR_WIRE YELLOW;
SET COLOR_PROP ORANGE;
SET COLOR_DOT WHITE;
SET COLOR_ARC YELLOW;
SET COLOR_BODY GREEN;
SET COLOR_NOTE PURPLE;
SET PROP_DISPLAY VALUE;
SET PAGE_NUMBER P267;
FORCEADD UNIVERSAL_GND..1
(-12850 1550);
FORCEPROP 3 LASTPIN (-12850 1600) SIG_NAME AGND_HSC\g
J 0
(-12840 1610);
DISPLAY 0.659574 (-12840 1610);
PAINT MONO (-12840 1610);
DISPLAY INVISIBLE (-12840 1610);
FORCEPROP 1 LAST HDL_POWER AGND_HSC
J 1
(-12850 1475);
DISPLAY 0.723404 (-12850 1475);
PAINT GREEN (-12850 1475);
FORCEPROP 2 LAST CDS_LIB pure_quanta_power
J 0
(-12850 1550);
DISPLAY INVISIBLE (-12850 1550);
FORCEPROP 1 LAST PATH I17
J 0
(-12775 1550);
DISPLAY 0.872340 (-12775 1550);
PAINT AQUA (-12775 1550);
DISPLAY INVISIBLE (-12775 1550);
FORCEADD UNIVERSAL_GND..1
(-9975 1250);
FORCEPROP 3 LASTPIN (-9975 1300) SIG_NAME AGND_HSC\g
J 0
(-9965 1310);
DISPLAY 0.659574 (-9965 1310);
PAINT MONO (-9965 1310);
DISPLAY INVISIBLE (-9965 1310);
FORCEPROP 1 LAST HDL_POWER AGND_HSC
J 1
(-9950 1175);
DISPLAY 0.723404 (-9950 1175);
PAINT GREEN (-9950 1175);
FORCEPROP 2 LAST CDS_LIB pure_quanta_power
J 0
(-9975 1250);
DISPLAY INVISIBLE (-9975 1250);
FORCEPROP 1 LAST PATH I21
J 0
(-9900 1250);
DISPLAY 0.872340 (-9900 1250);
PAINT AQUA (-9900 1250);
DISPLAY INVISIBLE (-9900 1250);
FORCEADD Q_RES..2
(-9975 1450);
FORCEPROP 1 LAST LOCATION R1117
J 0
(-9920 1625);
DISPLAY 0.723404 (-9920 1625);
PAINT AQUA (-9920 1625);
FORCEPROP 0 LAST $SEC 1
J 0
(-9900 1675);
DISPLAY 0.680851 (-9900 1675);
PAINT MONO (-9900 1675);
DISPLAY INVISIBLE (-9900 1675);
FORCEPROP 0 LAST CDS_SEC 1
J 0
(-9900 1675);
DISPLAY 1.021277 (-9900 1675);
DISPLAY INVISIBLE (-9900 1675);
FORCEPROP 1 LASTPIN (-9975 1550) $PN 1
J 0
(-9970 1512);
DISPLAY 0.787234 (-9970 1512);
PAINT MONO (-9970 1512);
FORCEPROP 1 LASTPIN (-9975 1350) $PN 2
J 0
(-9970 1360);
DISPLAY 0.787234 (-9970 1360);
PAINT MONO (-9970 1360);
FORCEPROP 1 LAST VALUE 6.19K
J 0
(-9920 1575);
DISPLAY 0.723404 (-9920 1575);
PAINT SKYBLUE (-9920 1575);
FORCEPROP 0 LAST ROOM HSC BOM1
J 0
(-9925 1275);
DISPLAY 0.680851 (-9925 1275);
FORCEPROP 1 LAST TOLERANCE 1%
J 0
(-9920 1525);
DISPLAY 0.723404 (-9920 1525);
PAINT SKYBLUE (-9920 1525);
FORCEPROP 1 LAST WATTAGE 1/16W
J 0
(-9925 1475);
DISPLAY 0.723404 (-9925 1475);
PAINT SKYBLUE (-9925 1475);
FORCEPROP 1 LAST MATERIAL CHIP
J 0
(-9925 1425);
DISPLAY 0.723404 (-9925 1425);
PAINT SKYBLUE (-9925 1425);
FORCEPROP 1 LAST PACK_TYPE 0402LF
J 0
(-9925 1325);
DISPLAY 0.723404 (-9925 1325);
PAINT SKYBLUE (-9925 1325);
FORCEPROP 2 LAST CDS_LIB pure_quanta
J 0
(-9975 1450);
DISPLAY INVISIBLE (-9975 1450);
FORCEPROP 1 LAST PATH I22
J 0
(-9925 1625);
DISPLAY 0.978723 (-9925 1625);
PAINT WHITE (-9925 1625);
DISPLAY INVISIBLE (-9925 1625);
FORCEPROP 1 LAST PART_NUMBER CS26192FB03
J 0
(-9925 1375);
DISPLAY 0.723404 (-9925 1375);
PAINT WHITE (-9925 1375);
DISPLAY INVISIBLE (-9925 1375);
FORCEADD OFFPAGE..5
(-15800 2500);
FORCEPROP 2 LAST $XR1 80 
J 0
(-16145 2500);
DISPLAY 0.638298 (-16145 2500);
PAINT MONO (-16145 2500);
FORCEPROP 2 LAST $XR0 268 
J 0
(-16055 2500);
DISPLAY 0.638298 (-16055 2500);
PAINT MONO (-16055 2500);
FORCEPROP 2 LAST CDS_LIB standard
J 2
(-15800 2500);
DISPLAY INVISIBLE (-15800 2500);
FORCEPROP 1 LAST OFFPAGE TRUE
J 0
(-15475 2375);
DISPLAY 0.872340 (-15475 2375);
PAINT AQUA (-15475 2375);
DISPLAY INVISIBLE (-15475 2375);
FORCEPROP 1 LAST COMMENT_BODY TRUE
J 0
(-15700 2425);
DISPLAY 1.170213 (-15700 2425);
PAINT GREEN (-15700 2425);
DISPLAY INVISIBLE (-15700 2425);
FORCEPROP 2 LAST PATH I23
J 0
(-16050 2550);
DISPLAY 1.021277 (-16050 2550);
DISPLAY INVISIBLE (-16050 2550);
FORCEADD Q_RES..1
(-14625 2500);
FORCEPROP 1 LAST LOCATION R3924
J 0
(-14975 2500);
DISPLAY 0.723404 (-14975 2500);
PAINT AQUA (-14975 2500);
FORCEPROP 0 LAST $SEC 1
J 0
(-14250 2575);
DISPLAY 0.680851 (-14250 2575);
PAINT MONO (-14250 2575);
DISPLAY INVISIBLE (-14250 2575);
FORCEPROP 0 LAST CDS_SEC 1
J 0
(-14250 2575);
DISPLAY 1.021277 (-14250 2575);
DISPLAY INVISIBLE (-14250 2575);
FORCEPROP 1 LASTPIN (-14725 2500) $PN 1
J 0
(-14713 2512);
DISPLAY 0.787234 (-14713 2512);
PAINT MONO (-14713 2512);
FORCEPROP 1 LASTPIN (-14525 2500) $PN 2
J 0
(-14563 2512);
DISPLAY 0.787234 (-14563 2512);
PAINT MONO (-14563 2512);
FORCEPROP 1 LAST PACK_TYPE 0402LF
J 0
(-14425 2450);
DISPLAY 0.723404 (-14425 2450);
PAINT SKYBLUE (-14425 2450);
FORCEPROP 0 LAST ROOM HSC BOM1
J 0
(-14775 2575);
DISPLAY 0.680851 (-14775 2575);
FORCEPROP 1 LAST TOLERANCE 5%
J 0
(-14550 2450);
DISPLAY 0.723404 (-14550 2450);
PAINT SKYBLUE (-14550 2450);
FORCEPROP 1 LAST VALUE 0
J 2
(-14500 2525);
DISPLAY 0.723404 (-14500 2525);
PAINT SKYBLUE (-14500 2525);
FORCEPROP 1 LAST WATTAGE 1/16W
J 2
(-14250 2525);
DISPLAY 0.723404 (-14250 2525);
PAINT SKYBLUE (-14250 2525);
FORCEPROP 1 LAST MATERIAL CHIP
J 0
(-14200 2450);
DISPLAY 0.723404 (-14200 2450);
PAINT SKYBLUE (-14200 2450);
FORCEPROP 2 LAST CDS_LIB pure_quanta
J 0
(-14625 2500);
DISPLAY INVISIBLE (-14625 2500);
FORCEPROP 1 LAST PATH I24
J 0
(-14675 2650);
DISPLAY 0.978723 (-14675 2650);
PAINT WHITE (-14675 2650);
DISPLAY INVISIBLE (-14675 2650);
FORCEPROP 1 LAST PART_NUMBER CS00002JB13
J 0
(-14975 2450);
DISPLAY 0.723404 (-14975 2450);
PAINT WHITE (-14975 2450);
DISPLAY INVISIBLE (-14975 2450);
FORCEADD OFFPAGE..3
R 2
(-15100 3075);
FORCEPROP 2 LAST $XR0 151 
J 0
(-15380 3075);
DISPLAY 0.638298 (-15380 3075);
PAINT MONO (-15380 3075);
FORCEPROP 2 LAST CDS_LIB standard
J 2
(-15100 3075);
DISPLAY INVISIBLE (-15100 3075);
FORCEPROP 1 LAST OFFPAGE TRUE
J 2
(-15425 2950);
DISPLAY 0.872340 (-15425 2950);
PAINT GREEN (-15425 2950);
DISPLAY INVISIBLE (-15425 2950);
FORCEPROP 1 LAST COMMENT_BODY TRUE
J 2
(-15050 2975);
DISPLAY 0.872340 (-15050 2975);
PAINT GREEN (-15050 2975);
DISPLAY INVISIBLE (-15050 2975);
FORCEPROP 2 LAST PATH I25
J 0
(-15375 3125);
DISPLAY 1.021277 (-15375 3125);
DISPLAY INVISIBLE (-15375 3125);
FORCEADD OFFPAGE..4
R 2
(-15100 3175);
FORCEPROP 2 LAST $XR0 151 
J 0
(-15352 3175);
DISPLAY 0.638298 (-15352 3175);
PAINT MONO (-15352 3175);
FORCEPROP 2 LAST CDS_LIB standard
J 0
(-15100 3175);
DISPLAY INVISIBLE (-15100 3175);
FORCEPROP 1 LAST OFFPAGE TRUE
J 2
(-15425 3050);
DISPLAY 0.872340 (-15425 3050);
PAINT GREEN (-15425 3050);
DISPLAY INVISIBLE (-15425 3050);
FORCEPROP 1 LAST COMMENT_BODY TRUE
J 2
(-15075 3075);
DISPLAY 0.872340 (-15075 3075);
PAINT GREEN (-15075 3075);
DISPLAY INVISIBLE (-15075 3075);
FORCEPROP 2 LAST PATH I26
J 0
(-15350 3225);
DISPLAY 1.021277 (-15350 3225);
DISPLAY INVISIBLE (-15350 3225);
FORCEADD Q_CAP..1
(-15425 3625);
FORCEPROP 1 LAST LOCATION PC2186
J 0
(-15350 3775);
DISPLAY 0.723404 (-15350 3775);
PAINT AQUA (-15350 3775);
FORCEPROP 0 LAST $SEC 1
J 0
(-15350 3825);
DISPLAY 0.680851 (-15350 3825);
PAINT MONO (-15350 3825);
DISPLAY INVISIBLE (-15350 3825);
FORCEPROP 0 LAST CDS_SEC 1
J 0
(-15350 3825);
DISPLAY 1.021277 (-15350 3825);
DISPLAY INVISIBLE (-15350 3825);
FORCEPROP 1 LASTPIN (-15425 3725) $PN 1
J 0
(-15415 3705);
DISPLAY 0.787234 (-15415 3705);
PAINT MONO (-15415 3705);
FORCEPROP 1 LASTPIN (-15425 3525) $PN 2
J 0
(-15415 3505);
DISPLAY 0.787234 (-15415 3505);
PAINT MONO (-15415 3505);
FORCEPROP 1 LAST PACK_TYPE C0402
J 0
(-15350 3525);
DISPLAY 0.723404 (-15350 3525);
PAINT SKYBLUE (-15350 3525);
FORCEPROP 1 LAST MATERIAL X6S
J 0
(-15350 3625);
DISPLAY 0.723404 (-15350 3625);
PAINT SKYBLUE (-15350 3625);
FORCEPROP 1 LAST VALUE 1UF
J 0
(-15350 3725);
DISPLAY 0.723404 (-15350 3725);
PAINT SKYBLUE (-15350 3725);
FORCEPROP 1 LAST VOLTAGE 25V
J 0
(-15350 3675);
DISPLAY 0.723404 (-15350 3675);
PAINT SKYBLUE (-15350 3675);
FORCEPROP 0 LAST ROOM HSC BOM1
J 0
(-15350 3825);
DISPLAY 0.680851 (-15350 3825);
FORCEPROP 1 LAST TOLERANCE 10%
J 0
(-15375 3575);
DISPLAY 0.978723 (-15375 3575);
PAINT SKYBLUE (-15375 3575);
DISPLAY INVISIBLE (-15375 3575);
FORCEPROP 2 LAST CDS_LIB pure_quanta
J 0
(-15425 3625);
DISPLAY INVISIBLE (-15425 3625);
FORCEPROP 1 LAST PATH I27
J 0
(-15375 3775);
DISPLAY 0.978723 (-15375 3775);
PAINT WHITE (-15375 3775);
DISPLAY INVISIBLE (-15375 3775);
FORCEPROP 1 LAST PART_NUMBER CH5104KEB02
J 0
(-15350 3575);
DISPLAY 0.723404 (-15350 3575);
PAINT WHITE (-15350 3575);
DISPLAY INVISIBLE (-15350 3575);
FORCEADD UNIVERSAL_GND..1
(-14925 3350);
FORCEPROP 3 LASTPIN (-14925 3400) SIG_NAME AGND_HSC\g
J 0
(-14915 3410);
DISPLAY 0.659574 (-14915 3410);
PAINT MONO (-14915 3410);
DISPLAY INVISIBLE (-14915 3410);
FORCEPROP 1 LAST HDL_POWER AGND_HSC
J 1
(-14900 3275);
DISPLAY 0.723404 (-14900 3275);
PAINT GREEN (-14900 3275);
FORCEPROP 2 LAST CDS_LIB pure_quanta_power
J 0
(-14925 3350);
DISPLAY INVISIBLE (-14925 3350);
FORCEPROP 1 LAST PATH I29
J 0
(-14850 3350);
DISPLAY 0.872340 (-14850 3350);
PAINT AQUA (-14850 3350);
DISPLAY INVISIBLE (-14850 3350);
FORCEADD Q_CAP..1
(-14925 3600);
FORCEPROP 1 LAST LOCATION PC2187
J 0
(-14850 3775);
DISPLAY 0.723404 (-14850 3775);
PAINT AQUA (-14850 3775);
FORCEPROP 0 LAST $SEC 1
J 0
(-14850 3825);
DISPLAY 0.680851 (-14850 3825);
PAINT MONO (-14850 3825);
DISPLAY INVISIBLE (-14850 3825);
FORCEPROP 0 LAST CDS_SEC 1
J 0
(-14850 3825);
DISPLAY 1.021277 (-14850 3825);
DISPLAY INVISIBLE (-14850 3825);
FORCEPROP 1 LASTPIN (-14925 3700) $PN 1
J 0
(-14915 3680);
DISPLAY 0.787234 (-14915 3680);
PAINT MONO (-14915 3680);
FORCEPROP 1 LASTPIN (-14925 3500) $PN 2
J 0
(-14915 3480);
DISPLAY 0.787234 (-14915 3480);
PAINT MONO (-14915 3480);
FORCEPROP 1 LAST MATERIAL X6S
J 0
(-14850 3625);
DISPLAY 0.723404 (-14850 3625);
PAINT SKYBLUE (-14850 3625);
FORCEPROP 1 LAST PACK_TYPE C0402
J 0
(-14850 3525);
DISPLAY 0.723404 (-14850 3525);
PAINT SKYBLUE (-14850 3525);
FORCEPROP 1 LAST VOLTAGE 25V
J 0
(-14850 3675);
DISPLAY 0.723404 (-14850 3675);
PAINT SKYBLUE (-14850 3675);
FORCEPROP 1 LAST VALUE 1UF
J 0
(-14850 3725);
DISPLAY 0.723404 (-14850 3725);
PAINT SKYBLUE (-14850 3725);
FORCEPROP 0 LAST ROOM HSC BOM1
J 0
(-14850 3825);
DISPLAY 0.680851 (-14850 3825);
FORCEPROP 2 LAST CDS_LIB pure_quanta
J 0
(-14925 3600);
DISPLAY INVISIBLE (-14925 3600);
FORCEPROP 1 LAST TOLERANCE 10%
J 0
(-14875 3550);
DISPLAY 0.978723 (-14875 3550);
PAINT SKYBLUE (-14875 3550);
DISPLAY INVISIBLE (-14875 3550);
FORCEPROP 1 LAST PATH I30
J 0
(-14875 3750);
DISPLAY 0.978723 (-14875 3750);
PAINT WHITE (-14875 3750);
DISPLAY INVISIBLE (-14875 3750);
FORCEPROP 1 LAST PART_NUMBER CH5104KEB02
J 0
(-14850 3575);
DISPLAY 0.723404 (-14850 3575);
PAINT WHITE (-14850 3575);
DISPLAY INVISIBLE (-14850 3575);
FORCEADD OFFPAGE..5
(-14300 2150);
FORCEPROP 2 LAST $XR1 265 
J 0
(-14705 2150);
DISPLAY 0.638298 (-14705 2150);
PAINT MONO (-14705 2150);
FORCEPROP 2 LAST $XR0 264 
J 0
(-14585 2150);
DISPLAY 0.638298 (-14585 2150);
PAINT MONO (-14585 2150);
FORCEPROP 2 LAST CDS_LIB standard
J 0
(-14300 2150);
DISPLAY INVISIBLE (-14300 2150);
FORCEPROP 1 LAST OFFPAGE TRUE
J 0
(-13975 2025);
DISPLAY 0.872340 (-13975 2025);
PAINT AQUA (-13975 2025);
DISPLAY INVISIBLE (-13975 2025);
FORCEPROP 1 LAST COMMENT_BODY TRUE
J 0
(-14200 2075);
DISPLAY 1.170213 (-14200 2075);
PAINT GREEN (-14200 2075);
DISPLAY INVISIBLE (-14200 2075);
FORCEPROP 2 LAST PATH I31
J 0
(-14575 2200);
DISPLAY 1.021277 (-14575 2200);
DISPLAY INVISIBLE (-14575 2200);
FORCEADD OFFPAGE..4
R 2
(-14300 2300);
FORCEPROP 2 LAST $XR1 268 
J 0
(-14672 2300);
DISPLAY 0.638298 (-14672 2300);
PAINT MONO (-14672 2300);
FORCEPROP 2 LAST $XR0 269 
J 0
(-14552 2300);
DISPLAY 0.638298 (-14552 2300);
PAINT MONO (-14552 2300);
FORCEPROP 2 LAST CDS_LIB standard
J 0
(-14300 2300);
DISPLAY INVISIBLE (-14300 2300);
FORCEPROP 1 LAST OFFPAGE TRUE
J 2
(-14625 2175);
DISPLAY 0.872340 (-14625 2175);
PAINT GREEN (-14625 2175);
DISPLAY INVISIBLE (-14625 2175);
FORCEPROP 1 LAST COMMENT_BODY TRUE
J 2
(-14275 2200);
DISPLAY 0.872340 (-14275 2200);
PAINT GREEN (-14275 2200);
DISPLAY INVISIBLE (-14275 2200);
FORCEPROP 2 LAST PATH I32
J 0
(-14550 2350);
DISPLAY 1.021277 (-14550 2350);
DISPLAY INVISIBLE (-14550 2350);
FORCEADD Q_RES..1
R 1
(-14225 2675);
FORCEPROP 1 LAST LOCATION R3925
J 0
(-14150 2825);
DISPLAY 0.723404 (-14150 2825);
PAINT AQUA (-14150 2825);
FORCEPROP 0 LAST $SEC 1
R 1
J 0
(-14150 2875);
DISPLAY 0.680851 (-14150 2875);
PAINT MONO (-14150 2875);
DISPLAY INVISIBLE (-14150 2875);
FORCEPROP 0 LAST CDS_SEC 1
R 1
J 0
(-14150 2875);
DISPLAY 1.021277 (-14150 2875);
DISPLAY INVISIBLE (-14150 2875);
FORCEPROP 1 LASTPIN (-14225 2575) $PN 1
R 1
J 0
(-14237 2587);
DISPLAY 0.787234 (-14237 2587);
PAINT MONO (-14237 2587);
FORCEPROP 1 LASTPIN (-14225 2775) $PN 2
R 1
J 0
(-14237 2737);
DISPLAY 0.787234 (-14237 2737);
PAINT MONO (-14237 2737);
FORCEPROP 1 LAST TOLERANCE 1%
J 0
(-14150 2725);
DISPLAY 0.723404 (-14150 2725);
PAINT SKYBLUE (-14150 2725);
FORCEPROP 1 LAST VALUE 1K
J 0
(-14150 2775);
DISPLAY 0.723404 (-14150 2775);
PAINT SKYBLUE (-14150 2775);
FORCEPROP 1 LAST PACK_TYPE 0402LF
J 0
(-14150 2675);
DISPLAY 0.723404 (-14150 2675);
PAINT SKYBLUE (-14150 2675);
FORCEPROP 1 LAST WATTAGE 1/16W
J 0
(-14150 2625);
DISPLAY 0.723404 (-14150 2625);
PAINT SKYBLUE (-14150 2625);
FORCEPROP 1 LAST MATERIAL CHIP
J 0
(-14150 2525);
DISPLAY 0.638298 (-14150 2525);
PAINT SKYBLUE (-14150 2525);
FORCEPROP 0 LAST ROOM HSC BOM1
J 0
(-14500 2675);
DISPLAY 0.680851 (-14500 2675);
FORCEPROP 2 LAST CDS_LIB pure_quanta
J 0
(-14225 2675);
DISPLAY INVISIBLE (-14225 2675);
FORCEPROP 1 LAST PATH I34
R 1
J 0
(-14375 2625);
DISPLAY 0.978723 (-14375 2625);
PAINT WHITE (-14375 2625);
DISPLAY INVISIBLE (-14375 2625);
FORCEPROP 1 LAST PART_NUMBER CS21002FB06
J 0
(-14150 2575);
DISPLAY 0.723404 (-14150 2575);
PAINT WHITE (-14150 2575);
DISPLAY INVISIBLE (-14150 2575);
FORCEADD UNIVERSAL_POWER..1
(-14225 2850);
FORCEPROP 3 LASTPIN (-14225 2800) SIG_NAME P3V3_AUX\g
J 0
(-14215 2810);
DISPLAY 0.659574 (-14215 2810);
PAINT MONO (-14215 2810);
DISPLAY INVISIBLE (-14215 2810);
FORCEPROP 1 LAST HDL_POWER P3V3_AUX
J 1
(-14225 2900);
DISPLAY 0.723404 (-14225 2900);
PAINT GREEN (-14225 2900);
FORCEPROP 2 LAST CDS_LIB pure_quanta_power
J 0
(-14225 2850);
DISPLAY INVISIBLE (-14225 2850);
FORCEPROP 1 LAST PATH I35
J 0
(-14175 2875);
DISPLAY 0.872340 (-14175 2875);
PAINT AQUA (-14175 2875);
DISPLAY INVISIBLE (-14175 2875);
FORCEADD Q_RES..1
(-13675 3075);
FORCEPROP 1 LAST LOCATION R1714
J 0
(-13950 3075);
DISPLAY 0.723404 (-13950 3075);
PAINT AQUA (-13950 3075);
FORCEPROP 0 LAST $SEC 1
J 0
(-13775 3150);
DISPLAY INVISIBLE (-13775 3150);
FORCEPROP 0 LAST CDS_SEC 1
J 0
(-13775 3150);
DISPLAY INVISIBLE (-13775 3150);
FORCEPROP 1 LASTPIN (-13775 3075) $PN 1
J 0
(-13763 3087);
DISPLAY 0.787234 (-13763 3087);
DISPLAY INVISIBLE (-13763 3087);
FORCEPROP 1 LASTPIN (-13575 3075) $PN 2
J 0
(-13613 3087);
DISPLAY 0.787234 (-13613 3087);
DISPLAY INVISIBLE (-13613 3087);
FORCEPROP 1 LAST VALUE 0
J 2
(-13525 3075);
DISPLAY 0.723404 (-13525 3075);
PAINT SKYBLUE (-13525 3075);
FORCEPROP 0 LAST ROOM HSC BOM1
J 0
(-14075 3125);
DISPLAY 0.680851 (-14075 3125);
FORCEPROP 1 LAST WATTAGE 1/16W
J 2
(-13275 3075);
DISPLAY 0.723404 (-13275 3075);
PAINT SKYBLUE (-13275 3075);
FORCEPROP 1 LAST TOLERANCE 5%
J 0
(-13600 3025);
DISPLAY 0.723404 (-13600 3025);
PAINT SKYBLUE (-13600 3025);
FORCEPROP 1 LAST PACK_TYPE 0402LF
J 0
(-13475 3025);
DISPLAY 0.723404 (-13475 3025);
PAINT SKYBLUE (-13475 3025);
FORCEPROP 1 LAST MATERIAL CHIP
J 0
(-13250 3025);
DISPLAY 0.723404 (-13250 3025);
PAINT SKYBLUE (-13250 3025);
FORCEPROP 2 LAST CDS_LIB pure_quanta
J 0
(-13675 3075);
PAINT MONO (-13675 3075);
DISPLAY INVISIBLE (-13675 3075);
FORCEPROP 1 LAST PATH I36
J 0
(-13725 3225);
DISPLAY 0.978723 (-13725 3225);
PAINT WHITE (-13725 3225);
DISPLAY INVISIBLE (-13725 3225);
FORCEPROP 1 LAST PART_NUMBER CS00002JB13
J 0
(-14000 3025);
DISPLAY 0.723404 (-14000 3025);
PAINT WHITE (-14000 3025);
DISPLAY INVISIBLE (-14000 3025);
FORCEADD Q_RES..1
(-13675 3175);
FORCEPROP 1 LAST LOCATION R3909
J 0
(-13950 3175);
DISPLAY 0.638298 (-13950 3175);
FORCEPROP 0 LAST $SEC 1
J 0
(-13475 3325);
DISPLAY 0.680851 (-13475 3325);
PAINT MONO (-13475 3325);
DISPLAY INVISIBLE (-13475 3325);
FORCEPROP 0 LAST CDS_SEC 1
J 0
(-13475 3325);
DISPLAY 1.021277 (-13475 3325);
DISPLAY INVISIBLE (-13475 3325);
FORCEPROP 1 LASTPIN (-13775 3175) $PN 1
J 0
(-13763 3187);
DISPLAY 0.787234 (-13763 3187);
PAINT MONO (-13763 3187);
FORCEPROP 1 LASTPIN (-13575 3175) $PN 2
J 0
(-13613 3187);
DISPLAY 0.787234 (-13613 3187);
PAINT MONO (-13613 3187);
FORCEPROP 1 LAST WATTAGE 1/16W
J 2
(-13475 3300);
DISPLAY 0.510638 (-13475 3300);
FORCEPROP 1 LAST VALUE 33.2
J 2
(-13475 3175);
DISPLAY 0.510638 (-13475 3175);
FORCEPROP 1 LAST PACK_TYPE 0402LF
J 0
(-13775 3300);
DISPLAY 0.510638 (-13775 3300);
FORCEPROP 1 LAST TOLERANCE 1%
J 0
(-13450 3175);
DISPLAY 0.510638 (-13450 3175);
FORCEPROP 1 LAST MATERIAL CHIP
J 0
(-13375 3175);
DISPLAY 0.510638 (-13375 3175);
FORCEPROP 0 LAST ROOM HSC BOM1
J 0
(-14075 3225);
DISPLAY 0.680851 (-14075 3225);
FORCEPROP 2 LAST CDS_LIB pure_quanta
J 0
(-13675 3175);
DISPLAY INVISIBLE (-13675 3175);
FORCEPROP 1 LAST PATH I37
J 0
(-13725 3325);
DISPLAY 0.978723 (-13725 3325);
PAINT WHITE (-13725 3325);
DISPLAY INVISIBLE (-13725 3325);
FORCEPROP 1 LAST PART_NUMBER CS03322FB03
J 0
(-13775 3250);
DISPLAY 0.510638 (-13775 3250);
DISPLAY INVISIBLE (-13775 3250);
FORCEADD UNIVERSAL_GND..1
(-13700 3575);
FORCEPROP 3 LASTPIN (-13700 3625) SIG_NAME AGND_HSC\g
J 0
(-13690 3635);
DISPLAY 0.659574 (-13690 3635);
PAINT MONO (-13690 3635);
DISPLAY INVISIBLE (-13690 3635);
FORCEPROP 1 LAST HDL_POWER AGND_HSC
J 1
(-13675 3500);
DISPLAY 0.723404 (-13675 3500);
PAINT GREEN (-13675 3500);
FORCEPROP 2 LAST CDS_LIB pure_quanta_power
J 0
(-13700 3575);
DISPLAY INVISIBLE (-13700 3575);
FORCEPROP 1 LAST PATH I38
J 0
(-13625 3575);
DISPLAY 0.872340 (-13625 3575);
PAINT AQUA (-13625 3575);
DISPLAY INVISIBLE (-13625 3575);
FORCEADD Q_RES..1
R 1
(-15225 4050);
FORCEPROP 1 LAST LOCATION PR2149
J 0
(-15150 4200);
DISPLAY 0.723404 (-15150 4200);
PAINT AQUA (-15150 4200);
FORCEPROP 0 LAST $SEC 1
R 1
J 0
(-15150 4250);
DISPLAY 0.680851 (-15150 4250);
PAINT MONO (-15150 4250);
DISPLAY INVISIBLE (-15150 4250);
FORCEPROP 0 LAST CDS_SEC 1
R 1
J 0
(-15150 4250);
DISPLAY 1.021277 (-15150 4250);
DISPLAY INVISIBLE (-15150 4250);
FORCEPROP 1 LASTPIN (-15225 3950) $PN 1
R 1
J 0
(-15237 3962);
DISPLAY 0.787234 (-15237 3962);
PAINT MONO (-15237 3962);
FORCEPROP 1 LASTPIN (-15225 4150) $PN 2
R 1
J 0
(-15237 4112);
DISPLAY 0.787234 (-15237 4112);
PAINT MONO (-15237 4112);
FORCEPROP 1 LAST VALUE 0
R 2
J 0
(-15125 4175);
DISPLAY 0.723404 (-15125 4175);
PAINT SKYBLUE (-15125 4175);
FORCEPROP 1 LAST MATERIAL CHIP
J 0
(-15150 3900);
DISPLAY 0.787234 (-15150 3900);
PAINT SKYBLUE (-15150 3900);
FORCEPROP 1 LAST WATTAGE 1/16W
J 0
(-15150 4000);
DISPLAY 0.723404 (-15150 4000);
PAINT SKYBLUE (-15150 4000);
FORCEPROP 1 LAST PACK_TYPE 0402LF
J 0
(-15150 4050);
DISPLAY 0.723404 (-15150 4050);
PAINT SKYBLUE (-15150 4050);
FORCEPROP 1 LAST TOLERANCE 5%
J 0
(-15150 4100);
DISPLAY 0.723404 (-15150 4100);
PAINT SKYBLUE (-15150 4100);
FORCEPROP 0 LAST ROOM HSC BOM1
J 0
(-15150 4275);
DISPLAY 0.680851 (-15150 4275);
FORCEPROP 2 LAST CDS_LIB pure_quanta
J 0
(-15225 4050);
DISPLAY INVISIBLE (-15225 4050);
FORCEPROP 1 LAST PATH I39
R 1
J 0
(-15375 4000);
DISPLAY 0.978723 (-15375 4000);
PAINT WHITE (-15375 4000);
DISPLAY INVISIBLE (-15375 4000);
FORCEPROP 1 LAST PART_NUMBER CS00002JB13
J 0
(-15150 3950);
DISPLAY 0.723404 (-15150 3950);
PAINT WHITE (-15150 3950);
DISPLAY INVISIBLE (-15150 3950);
FORCEADD UNIVERSAL_POWER..1
(-15225 4275);
FORCEPROP 3 LASTPIN (-15225 4225) SIG_NAME HSC_VDD\g
J 0
(-15215 4235);
DISPLAY 0.659574 (-15215 4235);
PAINT MONO (-15215 4235);
DISPLAY INVISIBLE (-15215 4235);
FORCEPROP 1 LAST HDL_POWER HSC_VDD
J 1
(-15225 4325);
DISPLAY 0.723404 (-15225 4325);
PAINT GREEN (-15225 4325);
FORCEPROP 2 LAST BOM_COST MIO_VRD_SB
J 0
(-15225 4375);
DISPLAY 0.617021 (-15225 4375);
PAINT PURPLE (-15225 4375);
DISPLAY INVISIBLE (-15225 4375);
FORCEPROP 2 LAST CDS_LIB pure_quanta_power
J 0
(-15225 4275);
DISPLAY INVISIBLE (-15225 4275);
FORCEPROP 1 LAST PATH I41
J 0
(-15175 4300);
DISPLAY 0.872340 (-15175 4300);
PAINT AQUA (-15175 4300);
DISPLAY INVISIBLE (-15175 4300);
FORCEADD GND..1
(-14225 3975);
FORCEPROP 3 LASTPIN (-14225 4025) SIG_NAME GND\g
J 0
(-14215 4035);
DISPLAY 0.659574 (-14215 4035);
PAINT MONO (-14215 4035);
DISPLAY INVISIBLE (-14215 4035);
FORCEPROP 2 LAST CDS_LIB pure_quanta_power
J 0
(-14225 3975);
DISPLAY INVISIBLE (-14225 3975);
FORCEPROP 1 LAST SIZE 1B
J 0
(-14150 3925);
DISPLAY 0.872340 (-14150 3925);
PAINT AQUA (-14150 3925);
DISPLAY INVISIBLE (-14150 3925);
FORCEPROP 1 LAST HDL_POWER GND
J 0
(-14225 4125);
DISPLAY 1.170213 (-14225 4125);
PAINT GREEN (-14225 4125);
DISPLAY INVISIBLE (-14225 4125);
FORCEPROP 1 LAST PATH I42
J 0
(-14150 3975);
DISPLAY 0.872340 (-14150 3975);
PAINT AQUA (-14150 3975);
DISPLAY INVISIBLE (-14150 3975);
FORCEADD UNIVERSAL_POWER..1
(-14225 4975);
FORCEPROP 3 LASTPIN (-14225 4925) SIG_NAME P12V_PSU\g
J 0
(-14215 4935);
DISPLAY 0.659574 (-14215 4935);
PAINT MONO (-14215 4935);
DISPLAY INVISIBLE (-14215 4935);
FORCEPROP 1 LAST HDL_POWER P12V_PSU
J 1
(-14225 5025);
DISPLAY 0.723404 (-14225 5025);
PAINT GREEN (-14225 5025);
FORCEPROP 2 LAST CDS_LIB pure_quanta_power
J 0
(-14225 4975);
DISPLAY INVISIBLE (-14225 4975);
FORCEPROP 2 LAST BOM_COST MIO_VRD_SB
J 0
(-14225 5075);
DISPLAY 0.617021 (-14225 5075);
PAINT PURPLE (-14225 5075);
DISPLAY INVISIBLE (-14225 5075);
FORCEPROP 1 LAST PATH I45
J 0
(-14175 5000);
DISPLAY 0.872340 (-14175 5000);
PAINT AQUA (-14175 5000);
DISPLAY INVISIBLE (-14175 5000);
FORCEADD Q_CAP..1
(-14225 4350);
FORCEPROP 1 LAST LOCATION PC2188
J 0
(-14175 4450);
DISPLAY 0.723404 (-14175 4450);
PAINT AQUA (-14175 4450);
FORCEPROP 0 LAST $SEC 1
J 0
(-14175 4500);
DISPLAY 0.680851 (-14175 4500);
PAINT MONO (-14175 4500);
DISPLAY INVISIBLE (-14175 4500);
FORCEPROP 0 LAST CDS_SEC 1
J 0
(-14175 4500);
DISPLAY 1.021277 (-14175 4500);
DISPLAY INVISIBLE (-14175 4500);
FORCEPROP 1 LASTPIN (-14225 4450) $PN 1
J 0
(-14215 4430);
DISPLAY 0.787234 (-14215 4430);
PAINT MONO (-14215 4430);
FORCEPROP 1 LASTPIN (-14225 4250) $PN 2
J 0
(-14215 4230);
DISPLAY 0.787234 (-14215 4230);
PAINT MONO (-14215 4230);
FORCEPROP 1 LAST PACK_TYPE C0402
J 0
(-14175 4200);
DISPLAY 0.723404 (-14175 4200);
PAINT SKYBLUE (-14175 4200);
FORCEPROP 1 LAST MATERIAL X6S
J 0
(-14175 4300);
DISPLAY 0.723404 (-14175 4300);
PAINT SKYBLUE (-14175 4300);
FORCEPROP 1 LAST VOLTAGE 25V
J 0
(-14175 4350);
DISPLAY 0.723404 (-14175 4350);
PAINT SKYBLUE (-14175 4350);
FORCEPROP 1 LAST VALUE 1UF
J 0
(-14175 4400);
DISPLAY 0.723404 (-14175 4400);
PAINT SKYBLUE (-14175 4400);
FORCEPROP 0 LAST ROOM HSC BOM1
J 0
(-14175 4550);
DISPLAY 0.680851 (-14175 4550);
FORCEPROP 1 LAST TOLERANCE 10%
J 0
(-14175 4300);
DISPLAY 0.978723 (-14175 4300);
PAINT SKYBLUE (-14175 4300);
DISPLAY INVISIBLE (-14175 4300);
FORCEPROP 2 LAST CDS_LIB pure_quanta
J 0
(-14225 4350);
DISPLAY INVISIBLE (-14225 4350);
FORCEPROP 1 LAST PATH I46
J 0
(-14175 4500);
DISPLAY 0.978723 (-14175 4500);
PAINT WHITE (-14175 4500);
DISPLAY INVISIBLE (-14175 4500);
FORCEPROP 1 LAST PART_NUMBER CH5104KEB02
J 0
(-14175 4250);
DISPLAY 0.723404 (-14175 4250);
PAINT WHITE (-14175 4250);
DISPLAY INVISIBLE (-14175 4250);
FORCEADD Q_RES..2
(-13700 3900);
FORCEPROP 1 LAST LOCATION PR3927
J 0
(-13655 4025);
DISPLAY 0.978723 (-13655 4025);
FORCEPROP 0 LAST $SEC 1
J 0
(-13650 4075);
DISPLAY 0.680851 (-13650 4075);
PAINT MONO (-13650 4075);
DISPLAY INVISIBLE (-13650 4075);
FORCEPROP 0 LAST CDS_SEC 1
J 0
(-13650 4075);
DISPLAY 1.021277 (-13650 4075);
DISPLAY INVISIBLE (-13650 4075);
FORCEPROP 1 LASTPIN (-13700 4000) $PN 1
J 0
(-13695 3962);
DISPLAY 0.787234 (-13695 3962);
PAINT MONO (-13695 3962);
FORCEPROP 1 LASTPIN (-13700 3800) $PN 2
J 0
(-13695 3810);
DISPLAY 0.787234 (-13695 3810);
PAINT MONO (-13695 3810);
FORCEPROP 1 LAST TOLERANCE 0.1%
J 0
(-13655 3925);
DISPLAY 0.638298 (-13655 3925);
FORCEPROP 1 LAST PACK_TYPE 0402LF
J 0
(-13660 3725);
DISPLAY 0.638298 (-13660 3725);
FORCEPROP 1 LAST MATERIAL CHIP
J 0
(-13660 3825);
DISPLAY 0.638298 (-13660 3825);
FORCEPROP 1 LAST WATTAGE 1/16W
J 0
(-13660 3875);
DISPLAY 0.638298 (-13660 3875);
FORCEPROP 0 LAST ROOM HSC BOM1
J 0
(-13975 3950);
DISPLAY 0.680851 (-13975 3950);
FORCEPROP 1 LAST VALUE 4.99K
J 0
(-13655 3975);
DISPLAY 0.638298 (-13655 3975);
FORCEPROP 2 LAST CDS_LIB pure_quanta
J 0
(-13700 3900);
DISPLAY INVISIBLE (-13700 3900);
FORCEPROP 1 LAST PATH I47
J 0
(-13650 4075);
DISPLAY 0.978723 (-13650 4075);
PAINT WHITE (-13650 4075);
DISPLAY INVISIBLE (-13650 4075);
FORCEPROP 1 LAST PART_NUMBER CS24992BB04
J 0
(-13660 3775);
DISPLAY 0.638298 (-13660 3775);
DISPLAY INVISIBLE (-13660 3775);
FORCEADD Q_RES..2
(-13700 4350);
FORCEPROP 1 LAST LOCATION PR3926
J 0
(-13655 4475);
DISPLAY 0.978723 (-13655 4475);
FORCEPROP 0 LAST $SEC 1
J 0
(-13650 4525);
DISPLAY 0.680851 (-13650 4525);
PAINT MONO (-13650 4525);
DISPLAY INVISIBLE (-13650 4525);
FORCEPROP 0 LAST CDS_SEC 1
J 0
(-13650 4525);
DISPLAY 1.021277 (-13650 4525);
DISPLAY INVISIBLE (-13650 4525);
FORCEPROP 1 LASTPIN (-13700 4450) $PN 1
J 0
(-13695 4412);
DISPLAY 0.787234 (-13695 4412);
PAINT MONO (-13695 4412);
FORCEPROP 1 LASTPIN (-13700 4250) $PN 2
J 0
(-13695 4260);
DISPLAY 0.787234 (-13695 4260);
PAINT MONO (-13695 4260);
FORCEPROP 1 LAST PACK_TYPE 0402LF
J 0
(-13660 4175);
DISPLAY 0.787234 (-13660 4175);
FORCEPROP 1 LAST VALUE 75K
J 0
(-13655 4425);
DISPLAY 0.787234 (-13655 4425);
FORCEPROP 0 LAST ROOM HSC BOM1
J 0
(-13675 4550);
DISPLAY 0.680851 (-13675 4550);
FORCEPROP 1 LAST TOLERANCE 0.1%
J 0
(-13655 4375);
DISPLAY 0.787234 (-13655 4375);
FORCEPROP 1 LAST WATTAGE 1/16W
J 0
(-13660 4325);
DISPLAY 0.787234 (-13660 4325);
FORCEPROP 1 LAST MATERIAL CHIP
J 0
(-13660 4275);
DISPLAY 0.787234 (-13660 4275);
FORCEPROP 2 LAST CDS_LIB pure_quanta
J 0
(-13700 4350);
DISPLAY INVISIBLE (-13700 4350);
FORCEPROP 1 LAST PATH I48
J 0
(-13650 4525);
DISPLAY 0.978723 (-13650 4525);
PAINT WHITE (-13650 4525);
DISPLAY INVISIBLE (-13650 4525);
FORCEPROP 1 LAST PART_NUMBER CS37502BB01
J 0
(-13660 4225);
DISPLAY 0.787234 (-13660 4225);
DISPLAY INVISIBLE (-13660 4225);
FORCEADD UNIVERSAL_GND..1
(-13325 1875);
FORCEPROP 3 LASTPIN (-13325 1925) SIG_NAME AGND_HSC\g
J 0
(-13315 1935);
DISPLAY 0.659574 (-13315 1935);
PAINT MONO (-13315 1935);
DISPLAY INVISIBLE (-13315 1935);
FORCEPROP 1 LAST HDL_POWER AGND_HSC
J 1
(-13300 1800);
DISPLAY 0.723404 (-13300 1800);
PAINT GREEN (-13300 1800);
FORCEPROP 2 LAST CDS_LIB pure_quanta_power
J 0
(-13325 1875);
DISPLAY INVISIBLE (-13325 1875);
FORCEPROP 1 LAST PATH I49
J 0
(-13250 1875);
DISPLAY 0.872340 (-13250 1875);
PAINT AQUA (-13250 1875);
DISPLAY INVISIBLE (-13250 1875);
FORCEADD Q_CAP..1
(-13325 2175);
FORCEPROP 1 LAST LOCATION PC2103
J 0
(-13275 2275);
DISPLAY 0.723404 (-13275 2275);
PAINT AQUA (-13275 2275);
FORCEPROP 0 LAST $SEC 1
J 0
(-13275 2325);
DISPLAY 0.680851 (-13275 2325);
PAINT MONO (-13275 2325);
DISPLAY INVISIBLE (-13275 2325);
FORCEPROP 0 LAST CDS_SEC 1
J 0
(-13275 2325);
DISPLAY 1.021277 (-13275 2325);
DISPLAY INVISIBLE (-13275 2325);
FORCEPROP 1 LASTPIN (-13325 2275) $PN 1
J 0
(-13315 2255);
DISPLAY 0.787234 (-13315 2255);
PAINT MONO (-13315 2255);
FORCEPROP 1 LASTPIN (-13325 2075) $PN 2
J 0
(-13315 2055);
DISPLAY 0.787234 (-13315 2055);
PAINT MONO (-13315 2055);
FORCEPROP 1 LAST VALUE 1UF
J 0
(-13275 2225);
DISPLAY 0.723404 (-13275 2225);
PAINT SKYBLUE (-13275 2225);
FORCEPROP 1 LAST VOLTAGE 25V
J 0
(-13275 2175);
DISPLAY 0.723404 (-13275 2175);
PAINT SKYBLUE (-13275 2175);
FORCEPROP 1 LAST MATERIAL X6S
J 0
(-13275 2125);
DISPLAY 0.723404 (-13275 2125);
PAINT SKYBLUE (-13275 2125);
FORCEPROP 1 LAST PACK_TYPE C0402
J 0
(-13275 2025);
DISPLAY 0.723404 (-13275 2025);
PAINT SKYBLUE (-13275 2025);
FORCEPROP 0 LAST ROOM HSC BOM1
J 0
(-13275 2325);
DISPLAY 0.680851 (-13275 2325);
FORCEPROP 2 LAST CDS_LIB pure_quanta
J 0
(-13325 2175);
DISPLAY INVISIBLE (-13325 2175);
FORCEPROP 1 LAST TOLERANCE 10%
J 0
(-13275 2125);
DISPLAY 0.978723 (-13275 2125);
PAINT SKYBLUE (-13275 2125);
DISPLAY INVISIBLE (-13275 2125);
FORCEPROP 1 LAST PATH I50
J 0
(-13275 2325);
DISPLAY 0.978723 (-13275 2325);
PAINT WHITE (-13275 2325);
DISPLAY INVISIBLE (-13275 2325);
FORCEPROP 1 LAST PART_NUMBER CH5104KEB02
J 0
(-13275 2075);
DISPLAY 0.723404 (-13275 2075);
PAINT WHITE (-13275 2075);
DISPLAY INVISIBLE (-13275 2075);
FORCEADD Q_RES..1
(-13100 2525);
FORCEPROP 1 LAST LOCATION PR3928
J 0
(-13425 2525);
DISPLAY 0.723404 (-13425 2525);
PAINT AQUA (-13425 2525);
FORCEPROP 0 LAST $SEC 1
J 0
(-12700 2575);
DISPLAY 0.680851 (-12700 2575);
PAINT MONO (-12700 2575);
DISPLAY INVISIBLE (-12700 2575);
FORCEPROP 0 LAST CDS_SEC 1
J 0
(-12700 2575);
DISPLAY 1.021277 (-12700 2575);
DISPLAY INVISIBLE (-12700 2575);
FORCEPROP 1 LASTPIN (-13200 2525) $PN 1
J 0
(-13188 2537);
DISPLAY 0.787234 (-13188 2537);
PAINT MONO (-13188 2537);
FORCEPROP 1 LASTPIN (-13000 2525) $PN 2
J 0
(-13038 2537);
DISPLAY 0.787234 (-13038 2537);
PAINT MONO (-13038 2537);
FORCEPROP 1 LAST WATTAGE 1/16W
J 2
(-12700 2525);
DISPLAY 0.723404 (-12700 2525);
PAINT SKYBLUE (-12700 2525);
FORCEPROP 1 LAST PACK_TYPE 0402LF
J 0
(-12925 2475);
DISPLAY 0.723404 (-12925 2475);
PAINT SKYBLUE (-12925 2475);
FORCEPROP 1 LAST MATERIAL CHIP
J 0
(-12700 2475);
DISPLAY 0.723404 (-12700 2475);
PAINT SKYBLUE (-12700 2475);
FORCEPROP 1 LAST TOLERANCE 5%
J 0
(-13025 2475);
DISPLAY 0.723404 (-13025 2475);
PAINT SKYBLUE (-13025 2475);
FORCEPROP 1 LAST VALUE 0
J 2
(-12950 2525);
DISPLAY 0.723404 (-12950 2525);
PAINT SKYBLUE (-12950 2525);
FORCEPROP 0 LAST ROOM HSC BOM1
J 0
(-13200 2425);
DISPLAY 0.680851 (-13200 2425);
FORCEPROP 2 LAST CDS_LIB pure_quanta
J 0
(-13100 2525);
DISPLAY INVISIBLE (-13100 2525);
FORCEPROP 1 LAST PATH I51
J 0
(-13150 2675);
DISPLAY 0.978723 (-13150 2675);
PAINT WHITE (-13150 2675);
DISPLAY INVISIBLE (-13150 2675);
FORCEPROP 1 LAST PART_NUMBER CS00002JB13
J 0
(-13425 2475);
DISPLAY 0.723404 (-13425 2475);
PAINT WHITE (-13425 2475);
DISPLAY INVISIBLE (-13425 2475);
FORCEADD Q_RES..1
R 1
(-12850 1750);
FORCEPROP 1 LAST LOCATION PR3930
J 0
(-12775 1875);
DISPLAY 0.723404 (-12775 1875);
PAINT AQUA (-12775 1875);
FORCEPROP 0 LAST $SEC 1
R 1
J 0
(-12775 1925);
DISPLAY 0.680851 (-12775 1925);
PAINT MONO (-12775 1925);
DISPLAY INVISIBLE (-12775 1925);
FORCEPROP 0 LAST CDS_SEC 1
R 1
J 0
(-12775 1925);
DISPLAY 1.021277 (-12775 1925);
DISPLAY INVISIBLE (-12775 1925);
FORCEPROP 1 LASTPIN (-12850 1650) $PN 1
R 1
J 0
(-12862 1662);
DISPLAY 0.787234 (-12862 1662);
PAINT MONO (-12862 1662);
FORCEPROP 1 LASTPIN (-12850 1850) $PN 2
R 1
J 0
(-12862 1812);
DISPLAY 0.787234 (-12862 1812);
PAINT MONO (-12862 1812);
FORCEPROP 1 LAST VALUE 0
J 0
(-12775 1825);
DISPLAY 0.723404 (-12775 1825);
PAINT SKYBLUE (-12775 1825);
FORCEPROP 1 LAST TOLERANCE 5%
J 0
(-12775 1775);
DISPLAY 0.723404 (-12775 1775);
PAINT SKYBLUE (-12775 1775);
FORCEPROP 1 LAST PACK_TYPE 0402LF
J 0
(-12775 1725);
DISPLAY 0.723404 (-12775 1725);
PAINT SKYBLUE (-12775 1725);
FORCEPROP 1 LAST MATERIAL CHIP
J 0
(-12775 1575);
DISPLAY 0.808511 (-12775 1575);
PAINT SKYBLUE (-12775 1575);
FORCEPROP 1 LAST WATTAGE 1/16W
J 0
(-12775 1675);
DISPLAY 0.723404 (-12775 1675);
PAINT SKYBLUE (-12775 1675);
FORCEPROP 0 LAST ROOM HSC BOM1
J 0
(-12700 1825);
DISPLAY 0.680851 (-12700 1825);
FORCEPROP 2 LAST CDS_LIB pure_quanta
J 0
(-12850 1750);
DISPLAY INVISIBLE (-12850 1750);
FORCEPROP 1 LAST PATH I52
R 1
J 0
(-13000 1700);
DISPLAY 0.978723 (-13000 1700);
PAINT WHITE (-13000 1700);
DISPLAY INVISIBLE (-13000 1700);
FORCEPROP 1 LAST PART_NUMBER CS00002JB13
J 0
(-12775 1625);
DISPLAY 0.723404 (-12775 1625);
PAINT WHITE (-12775 1625);
DISPLAY INVISIBLE (-12775 1625);
FORCEADD Q_RES..1
R 1
(-12850 2150);
FORCEPROP 1 LAST LOCATION PR3929
J 0
(-12775 2300);
DISPLAY 0.723404 (-12775 2300);
PAINT AQUA (-12775 2300);
FORCEPROP 0 LAST $SEC 1
R 1
J 0
(-12775 2350);
DISPLAY 0.680851 (-12775 2350);
PAINT MONO (-12775 2350);
DISPLAY INVISIBLE (-12775 2350);
FORCEPROP 0 LAST CDS_SEC 1
R 1
J 0
(-12775 2350);
DISPLAY 1.021277 (-12775 2350);
DISPLAY INVISIBLE (-12775 2350);
FORCEPROP 1 LASTPIN (-12850 2050) $PN 1
R 1
J 0
(-12862 2062);
DISPLAY 0.787234 (-12862 2062);
PAINT MONO (-12862 2062);
FORCEPROP 1 LASTPIN (-12850 2250) $PN 2
R 1
J 0
(-12862 2212);
DISPLAY 0.787234 (-12862 2212);
PAINT MONO (-12862 2212);
FORCEPROP 1 LAST MATERIAL EMPTY
J 0
(-12775 2000);
DISPLAY 0.638298 (-12775 2000);
PAINT RED (-12775 2000);
FORCEPROP 1 LAST PACK_TYPE 0402LF
J 0
(-12775 2150);
DISPLAY 0.723404 (-12775 2150);
PAINT SKYBLUE (-12775 2150);
FORCEPROP 1 LAST WATTAGE 1/16W
J 0
(-12775 2100);
DISPLAY 0.723404 (-12775 2100);
PAINT SKYBLUE (-12775 2100);
FORCEPROP 1 LAST TOLERANCE 1%
J 0
(-12775 2200);
DISPLAY 0.723404 (-12775 2200);
PAINT SKYBLUE (-12775 2200);
FORCEPROP 1 LAST VALUE 1K
J 0
(-12775 2250);
DISPLAY 0.723404 (-12775 2250);
PAINT SKYBLUE (-12775 2250);
FORCEPROP 0 LAST ROOM HSC BOM1
J 0
(-12675 2250);
DISPLAY 0.553191 (-12675 2250);
FORCEPROP 2 LAST CDS_LIB pure_quanta
J 0
(-12850 2150);
DISPLAY INVISIBLE (-12850 2150);
FORCEPROP 1 LAST PATH I53
R 1
J 0
(-13000 2100);
DISPLAY 0.978723 (-13000 2100);
PAINT WHITE (-13000 2100);
DISPLAY INVISIBLE (-13000 2100);
FORCEPROP 1 LAST PART_NUMBER CS21002FB06
J 0
(-12775 2050);
DISPLAY 0.723404 (-12775 2050);
PAINT WHITE (-12775 2050);
DISPLAY INVISIBLE (-12775 2050);
FORCEADD Q_RES..1
(-13100 2650);
FORCEPROP 1 LAST LOCATION R2586
J 0
(-13425 2650);
DISPLAY 0.723404 (-13425 2650);
PAINT AQUA (-13425 2650);
FORCEPROP 0 LAST $SEC 1
J 0
(-12700 2700);
DISPLAY 0.680851 (-12700 2700);
PAINT MONO (-12700 2700);
DISPLAY INVISIBLE (-12700 2700);
FORCEPROP 0 LAST CDS_SEC 1
J 0
(-12700 2700);
DISPLAY 1.021277 (-12700 2700);
DISPLAY INVISIBLE (-12700 2700);
FORCEPROP 1 LASTPIN (-13200 2650) $PN 1
J 0
(-13188 2662);
DISPLAY 0.787234 (-13188 2662);
PAINT MONO (-13188 2662);
FORCEPROP 1 LASTPIN (-13000 2650) $PN 2
J 0
(-13038 2662);
DISPLAY 0.787234 (-13038 2662);
PAINT MONO (-13038 2662);
FORCEPROP 1 LAST VALUE 0
J 2
(-12950 2650);
DISPLAY 0.723404 (-12950 2650);
PAINT SKYBLUE (-12950 2650);
FORCEPROP 1 LAST MATERIAL CHIP
J 0
(-12700 2600);
DISPLAY 0.723404 (-12700 2600);
PAINT SKYBLUE (-12700 2600);
FORCEPROP 0 LAST ROOM HSC BOM1
J 0
(-13700 2650);
DISPLAY 0.680851 (-13700 2650);
FORCEPROP 1 LAST WATTAGE 1/16W
J 2
(-12700 2650);
DISPLAY 0.723404 (-12700 2650);
PAINT SKYBLUE (-12700 2650);
FORCEPROP 1 LAST PACK_TYPE 0402LF
J 0
(-12925 2600);
DISPLAY 0.723404 (-12925 2600);
PAINT SKYBLUE (-12925 2600);
FORCEPROP 1 LAST TOLERANCE 5%
J 0
(-13025 2600);
DISPLAY 0.723404 (-13025 2600);
PAINT SKYBLUE (-13025 2600);
FORCEPROP 2 LAST CDS_LIB pure_quanta
J 0
(-13100 2650);
DISPLAY INVISIBLE (-13100 2650);
FORCEPROP 1 LAST PATH I54
J 0
(-13150 2800);
DISPLAY 0.978723 (-13150 2800);
PAINT WHITE (-13150 2800);
DISPLAY INVISIBLE (-13150 2800);
FORCEPROP 1 LAST PART_NUMBER CS00002JB13
J 0
(-13425 2600);
DISPLAY 0.723404 (-13425 2600);
PAINT WHITE (-13425 2600);
DISPLAY INVISIBLE (-13425 2600);
FORCEADD UNIVERSAL_POWER..1
(-13600 2850);
FORCEPROP 3 LASTPIN (-13600 2800) SIG_NAME HSC_VDD\g
J 0
(-13590 2810);
DISPLAY 0.659574 (-13590 2810);
PAINT MONO (-13590 2810);
DISPLAY INVISIBLE (-13590 2810);
FORCEPROP 2 LAST ROOM AUX_SW
J 0
(-13600 2950);
DISPLAY 0.617021 (-13600 2950);
FORCEPROP 1 LAST HDL_POWER HSC_VDD
J 1
(-13600 2900);
DISPLAY 0.723404 (-13600 2900);
PAINT GREEN (-13600 2900);
FORCEPROP 2 LAST BOM_COST MIO_VRD_SB
J 0
(-13600 2950);
DISPLAY 0.617021 (-13600 2950);
PAINT PURPLE (-13600 2950);
DISPLAY INVISIBLE (-13600 2950);
FORCEPROP 2 LAST CDS_LIB pure_quanta_power
J 0
(-13600 2850);
DISPLAY INVISIBLE (-13600 2850);
FORCEPROP 1 LAST PATH I55
J 0
(-13550 2875);
DISPLAY 0.872340 (-13550 2875);
PAINT AQUA (-13550 2875);
DISPLAY INVISIBLE (-13550 2875);
FORCEADD Q_RES..1
(-13100 2775);
FORCEPROP 1 LAST LOCATION PR2106
J 0
(-13425 2775);
DISPLAY 0.723404 (-13425 2775);
PAINT AQUA (-13425 2775);
FORCEPROP 0 LAST $SEC 1
J 0
(-12700 2825);
DISPLAY 0.680851 (-12700 2825);
PAINT MONO (-12700 2825);
DISPLAY INVISIBLE (-12700 2825);
FORCEPROP 0 LAST CDS_SEC 1
J 0
(-12700 2825);
DISPLAY 1.021277 (-12700 2825);
DISPLAY INVISIBLE (-12700 2825);
FORCEPROP 1 LASTPIN (-13200 2775) $PN 1
J 0
(-13188 2787);
DISPLAY 0.787234 (-13188 2787);
PAINT MONO (-13188 2787);
FORCEPROP 1 LASTPIN (-13000 2775) $PN 2
J 0
(-13038 2787);
DISPLAY 0.787234 (-13038 2787);
PAINT MONO (-13038 2787);
FORCEPROP 1 LAST VALUE 10K
J 2
(-12925 2775);
DISPLAY 0.723404 (-12925 2775);
PAINT SKYBLUE (-12925 2775);
FORCEPROP 0 LAST ROOM HSC BOM1
J 0
(-13450 2825);
DISPLAY 0.680851 (-13450 2825);
FORCEPROP 1 LAST WATTAGE 1/16W
J 2
(-12700 2775);
DISPLAY 0.723404 (-12700 2775);
PAINT SKYBLUE (-12700 2775);
FORCEPROP 1 LAST TOLERANCE 1%
J 0
(-13025 2725);
DISPLAY 0.723404 (-13025 2725);
PAINT SKYBLUE (-13025 2725);
FORCEPROP 1 LAST PACK_TYPE 0402LF
J 0
(-12925 2725);
DISPLAY 0.723404 (-12925 2725);
PAINT SKYBLUE (-12925 2725);
FORCEPROP 1 LAST MATERIAL CHIP
J 0
(-12700 2725);
DISPLAY 0.723404 (-12700 2725);
PAINT SKYBLUE (-12700 2725);
FORCEPROP 2 LAST CDS_LIB pure_quanta
J 0
(-13100 2775);
DISPLAY INVISIBLE (-13100 2775);
FORCEPROP 1 LAST PATH I56
J 0
(-13150 2925);
DISPLAY 0.978723 (-13150 2925);
PAINT WHITE (-13150 2925);
DISPLAY INVISIBLE (-13150 2925);
FORCEPROP 1 LAST PART_NUMBER CS31002FB08
J 0
(-13425 2725);
DISPLAY 0.723404 (-13425 2725);
PAINT WHITE (-13425 2725);
DISPLAY INVISIBLE (-13425 2725);
FORCEADD UNIVERSAL_GND..1
(-12075 1925);
FORCEPROP 3 LASTPIN (-12075 1975) SIG_NAME AGND_HSC\g
J 0
(-12065 1985);
DISPLAY 0.659574 (-12065 1985);
PAINT MONO (-12065 1985);
DISPLAY INVISIBLE (-12065 1985);
FORCEPROP 1 LAST HDL_POWER AGND_HSC
J 1
(-12050 1850);
DISPLAY 0.723404 (-12050 1850);
PAINT GREEN (-12050 1850);
FORCEPROP 2 LAST CDS_LIB pure_quanta_power
J 0
(-12075 1925);
DISPLAY INVISIBLE (-12075 1925);
FORCEPROP 1 LAST PATH I57
J 0
(-12000 1925);
DISPLAY 0.872340 (-12000 1925);
PAINT AQUA (-12000 1925);
DISPLAY INVISIBLE (-12000 1925);
FORCEADD MP5990GMA1111Z..1
(-11400 3050);
FORCEPROP 1 LAST LOCATION PU289
J 0
(-11800 4350);
DISPLAY 0.723404 (-11800 4350);
PAINT GREEN (-11800 4350);
FORCEPROP 0 LAST $SEC 1
J 0
(-11800 4500);
DISPLAY 0.680851 (-11800 4500);
PAINT MONO (-11800 4500);
DISPLAY INVISIBLE (-11800 4500);
FORCEPROP 0 LAST CDS_SEC 1
J 0
(-11800 4500);
DISPLAY 1.021277 (-11800 4500);
DISPLAY INVISIBLE (-11800 4500);
FORCEPROP 0 LASTPIN (-11975 2225) $PN 23
J 2
(-11985 2235);
DISPLAY 0.680851 (-11985 2235);
PAINT MONO (-11985 2235);
FORCEPROP 0 LASTPIN (-11975 2975) $PN 10
J 2
(-11985 2985);
DISPLAY 0.680851 (-11985 2985);
PAINT MONO (-11985 2985);
FORCEPROP 0 LASTPIN (-10825 2975) $PN 20
J 0
(-10815 2985);
DISPLAY 0.680851 (-10815 2985);
PAINT MONO (-10815 2985);
FORCEPROP 0 LASTPIN (-10825 3275) $PN 37
J 0
(-10815 3285);
DISPLAY 0.680851 (-10815 3285);
PAINT MONO (-10815 3285);
FORCEPROP 0 LASTPIN (-11975 2775) $PN 26
J 2
(-11985 2785);
DISPLAY 0.680851 (-11985 2785);
PAINT MONO (-11985 2785);
FORCEPROP 0 LASTPIN (-10825 2275) $PN 40
J 0
(-10815 2285);
DISPLAY 0.680851 (-10815 2285);
PAINT MONO (-10815 2285);
FORCEPROP 0 LASTPIN (-11975 2075) $PN 18
J 2
(-11985 2085);
DISPLAY 0.680851 (-11985 2085);
PAINT MONO (-11985 2085);
FORCEPROP 0 LASTPIN (-11975 2025) $PN 44
J 2
(-11985 2035);
DISPLAY 0.680851 (-11985 2035);
PAINT MONO (-11985 2035);
FORCEPROP 0 LASTPIN (-10825 3375) $PN 39
J 0
(-10815 3385);
DISPLAY 0.680851 (-10815 3385);
PAINT MONO (-10815 3385);
FORCEPROP 0 LASTPIN (-10825 3075) $PN 21
J 0
(-10815 3085);
DISPLAY 0.680851 (-10815 3085);
PAINT MONO (-10815 3085);
FORCEPROP 0 LASTPIN (-10825 3175) $PN 41
J 0
(-10815 3185);
DISPLAY 0.680851 (-10815 3185);
PAINT MONO (-10815 3185);
FORCEPROP 0 LASTPIN (-10825 2575) $PN 22
J 0
(-10815 2585);
DISPLAY 0.680851 (-10815 2585);
PAINT MONO (-10815 2585);
FORCEPROP 0 LASTPIN (-11975 2525) $PN 38
J 2
(-11985 2535);
DISPLAY 0.680851 (-11985 2535);
PAINT MONO (-11985 2535);
FORCEPROP 0 LASTPIN (-10825 2075) $PN 13
J 0
(-10815 2085);
DISPLAY 0.680851 (-10815 2085);
PAINT MONO (-10815 2085);
FORCEPROP 0 LASTPIN (-11975 3175) $PN 11
J 2
(-11985 3185);
DISPLAY 0.680851 (-11985 3185);
PAINT MONO (-11985 3185);
FORCEPROP 0 LASTPIN (-10825 2475) $PN 25
J 0
(-10815 2485);
DISPLAY 0.680851 (-10815 2485);
PAINT MONO (-10815 2485);
FORCEPROP 0 LASTPIN (-11975 3075) $PN 12
J 2
(-11985 3085);
DISPLAY 0.680851 (-11985 3085);
PAINT MONO (-11985 3085);
FORCEPROP 0 LASTPIN (-10825 2375) $PN 16
J 0
(-10815 2385);
DISPLAY 0.680851 (-10815 2385);
PAINT MONO (-10815 2385);
FORCEPROP 0 LASTPIN (-11975 2375) $PN 19
J 2
(-11985 2385);
DISPLAY 0.680851 (-11985 2385);
PAINT MONO (-11985 2385);
FORCEPROP 0 LASTPIN (-11975 3375) $PN 17
J 2
(-11985 3385);
DISPLAY 0.680851 (-11985 3385);
PAINT MONO (-11985 3385);
FORCEPROP 0 LASTPIN (-11975 3325) $PN 45
J 2
(-11985 3335);
DISPLAY 0.680851 (-11985 3335);
PAINT MONO (-11985 3335);
FORCEPROP 0 LASTPIN (-11975 4125) $PN 1
J 2
(-11985 4135);
DISPLAY 0.680851 (-11985 4135);
PAINT MONO (-11985 4135);
FORCEPROP 0 LASTPIN (-11975 4075) $PN 2
J 2
(-11985 4085);
DISPLAY 0.680851 (-11985 4085);
PAINT MONO (-11985 4085);
FORCEPROP 0 LASTPIN (-11975 4025) $PN 3
J 2
(-11985 4035);
DISPLAY 0.680851 (-11985 4035);
PAINT MONO (-11985 4035);
FORCEPROP 0 LASTPIN (-11975 3975) $PN 4
J 2
(-11985 3985);
DISPLAY 0.680851 (-11985 3985);
PAINT MONO (-11985 3985);
FORCEPROP 0 LASTPIN (-11975 3925) $PN 5
J 2
(-11985 3935);
DISPLAY 0.680851 (-11985 3935);
PAINT MONO (-11985 3935);
FORCEPROP 0 LASTPIN (-11975 3875) $PN 6
J 2
(-11985 3885);
DISPLAY 0.680851 (-11985 3885);
PAINT MONO (-11985 3885);
FORCEPROP 0 LASTPIN (-11975 3825) $PN 7
J 2
(-11985 3835);
DISPLAY 0.680851 (-11985 3835);
PAINT MONO (-11985 3835);
FORCEPROP 0 LASTPIN (-11975 3775) $PN 8
J 2
(-11985 3785);
DISPLAY 0.680851 (-11985 3785);
PAINT MONO (-11985 3785);
FORCEPROP 0 LASTPIN (-11975 3725) $PN 42
J 2
(-11985 3735);
DISPLAY 0.680851 (-11985 3735);
PAINT MONO (-11985 3735);
FORCEPROP 0 LASTPIN (-11975 3675) $PN 43
J 2
(-11985 3685);
DISPLAY 0.680851 (-11985 3685);
PAINT MONO (-11985 3685);
FORCEPROP 0 LASTPIN (-11975 2875) $PN 14
J 2
(-11985 2885);
DISPLAY 0.680851 (-11985 2885);
PAINT MONO (-11985 2885);
FORCEPROP 0 LASTPIN (-11975 3575) $PN 9
J 2
(-11985 3585);
DISPLAY 0.680851 (-11985 3585);
PAINT MONO (-11985 3585);
FORCEPROP 0 LASTPIN (-10825 3575) $PN 24
J 0
(-10815 3585);
DISPLAY 0.680851 (-10815 3585);
PAINT MONO (-10815 3585);
FORCEPROP 0 LASTPIN (-10825 4125) $PN 27
J 0
(-10815 4135);
DISPLAY 0.680851 (-10815 4135);
PAINT MONO (-10815 4135);
FORCEPROP 0 LASTPIN (-10825 4075) $PN 28
J 0
(-10815 4085);
DISPLAY 0.680851 (-10815 4085);
PAINT MONO (-10815 4085);
FORCEPROP 0 LASTPIN (-10825 4025) $PN 29
J 0
(-10815 4035);
DISPLAY 0.680851 (-10815 4035);
PAINT MONO (-10815 4035);
FORCEPROP 0 LASTPIN (-10825 3975) $PN 30
J 0
(-10815 3985);
DISPLAY 0.680851 (-10815 3985);
PAINT MONO (-10815 3985);
FORCEPROP 0 LASTPIN (-10825 3925) $PN 31
J 0
(-10815 3935);
DISPLAY 0.680851 (-10815 3935);
PAINT MONO (-10815 3935);
FORCEPROP 0 LASTPIN (-10825 3875) $PN 32
J 0
(-10815 3885);
DISPLAY 0.680851 (-10815 3885);
PAINT MONO (-10815 3885);
FORCEPROP 0 LASTPIN (-10825 3825) $PN 33
J 0
(-10815 3835);
DISPLAY 0.680851 (-10815 3835);
PAINT MONO (-10815 3835);
FORCEPROP 0 LASTPIN (-10825 3775) $PN 34
J 0
(-10815 3785);
DISPLAY 0.680851 (-10815 3785);
PAINT MONO (-10815 3785);
FORCEPROP 0 LASTPIN (-10825 3725) $PN 35
J 0
(-10815 3735);
DISPLAY 0.680851 (-10815 3735);
PAINT MONO (-10815 3735);
FORCEPROP 0 LASTPIN (-10825 3675) $PN 36
J 0
(-10815 3685);
DISPLAY 0.680851 (-10815 3685);
PAINT MONO (-10815 3685);
FORCEPROP 0 LASTPIN (-10825 2675) $PN 15
J 0
(-10815 2685);
DISPLAY 0.680851 (-10815 2685);
PAINT MONO (-10815 2685);
FORCEPROP 0 LAST ROOM HSC BOM1
J 0
(-11800 4550);
DISPLAY 0.680851 (-11800 4550);
FORCEPROP 2 LAST PART_TYPE SMLF
J 0
(-11800 4450);
DISPLAY 1.021277 (-11800 4450);
FORCEPROP 2 LAST VALUE MP5990GMA-1111-Z
J 0
(-11800 4400);
DISPLAY 1.021277 (-11800 4400);
FORCEPROP 2 LASTPIN (-10825 3575) SIG_NAME HSC_VOSEN
J 0
(-10710 3585);
DISPLAY 0.808511 (-10710 3585);
FORCEPROP 2 LASTPROP $XRERR UNIQUE?
J 0
(-10950 3585);
DISPLAY 0.638298 (-10950 3585);
PAINT MONO (-10950 3585);
DISPLAY INVISIBLE (-10950 3585);
FORCEPROP 1 LAST MATERIAL IC
J 0
(-11820 4187);
DISPLAY 0.723404 (-11820 4187);
PAINT GREEN (-11820 4187);
FORCEPROP 2 LAST CDS_LIB pure_quanta
J 0
(-11400 3050);
DISPLAY INVISIBLE (-11400 3050);
FORCEPROP 1 LAST NEEDS_NO_SIZE TRUE
J 0
(-11400 3050);
DISPLAY 0.723404 (-11400 3050);
PAINT GREEN (-11400 3050);
DISPLAY INVISIBLE (-11400 3050);
FORCEPROP 1 LAST CDS_LMAN_SYM_OUTLINE -425,1125,425,-1125
J 0
(-11400 3050);
DISPLAY 0.468085 (-11400 3050);
PAINT GREEN (-11400 3050);
DISPLAY INVISIBLE (-11400 3050);
FORCEPROP 1 LAST PATH I58
J 0
(-11400 3050);
DISPLAY 0.723404 (-11400 3050);
PAINT GREEN (-11400 3050);
DISPLAY INVISIBLE (-11400 3050);
FORCEPROP 1 LAST PART_NUMBER AR0F0TP4023
J 0
(-11800 4300);
DISPLAY 0.723404 (-11800 4300);
PAINT GREEN (-11800 4300);
DISPLAY INVISIBLE (-11800 4300);
FORCEADD Q_CAP..1
(-13175 3900);
FORCEPROP 1 LAST LOCATION PC2189
J 0
(-13100 3975);
DISPLAY 0.723404 (-13100 3975);
PAINT AQUA (-13100 3975);
FORCEPROP 0 LAST $SEC 1
J 0
(-13100 4100);
DISPLAY 0.680851 (-13100 4100);
PAINT MONO (-13100 4100);
DISPLAY INVISIBLE (-13100 4100);
FORCEPROP 0 LAST CDS_SEC 1
J 0
(-13100 4100);
DISPLAY 1.021277 (-13100 4100);
DISPLAY INVISIBLE (-13100 4100);
FORCEPROP 1 LASTPIN (-13175 4000) $PN 1
J 0
(-13165 3980);
DISPLAY 0.787234 (-13165 3980);
PAINT MONO (-13165 3980);
FORCEPROP 1 LASTPIN (-13175 3800) $PN 2
J 0
(-13165 3780);
DISPLAY 0.787234 (-13165 3780);
PAINT MONO (-13165 3780);
FORCEPROP 1 LAST VALUE 0.01UF
J 0
(-13100 3925);
DISPLAY 0.723404 (-13100 3925);
PAINT SKYBLUE (-13100 3925);
FORCEPROP 0 LAST ROOM HSC BOM1
J 0
(-13100 4050);
DISPLAY 0.680851 (-13100 4050);
FORCEPROP 1 LAST VOLTAGE 50V
J 0
(-13100 3875);
DISPLAY 0.723404 (-13100 3875);
PAINT SKYBLUE (-13100 3875);
FORCEPROP 1 LAST MATERIAL X7R
J 0
(-13100 3825);
DISPLAY 0.723404 (-13100 3825);
PAINT SKYBLUE (-13100 3825);
FORCEPROP 1 LAST PACK_TYPE C0402
J 0
(-13100 3725);
DISPLAY 0.723404 (-13100 3725);
PAINT SKYBLUE (-13100 3725);
FORCEPROP 1 LAST TOLERANCE 10%
J 0
(-13125 3850);
DISPLAY 0.978723 (-13125 3850);
PAINT SKYBLUE (-13125 3850);
DISPLAY INVISIBLE (-13125 3850);
FORCEPROP 2 LAST CDS_LIB pure_quanta
J 0
(-13175 3900);
DISPLAY INVISIBLE (-13175 3900);
FORCEPROP 1 LAST PATH I59
J 0
(-13125 4050);
DISPLAY 0.978723 (-13125 4050);
PAINT WHITE (-13125 4050);
DISPLAY INVISIBLE (-13125 4050);
FORCEPROP 1 LAST PART_NUMBER CH31006KB18
J 0
(-13100 3775);
DISPLAY 0.723404 (-13100 3775);
PAINT WHITE (-13100 3775);
DISPLAY INVISIBLE (-13100 3775);
FORCEADD OFFPAGE..5
R 2
(-10150 2275);
FORCEPROP 2 LAST $XR1 265 
J 0
(-9841 2275);
DISPLAY 0.638298 (-9841 2275);
PAINT MONO (-9841 2275);
FORCEPROP 2 LAST $XR0 264 
J 0
(-9961 2275);
DISPLAY 0.638298 (-9961 2275);
PAINT MONO (-9961 2275);
FORCEPROP 2 LAST CDS_LIB standard
J 0
(-10150 2275);
DISPLAY INVISIBLE (-10150 2275);
FORCEPROP 1 LAST OFFPAGE TRUE
J 2
(-10475 2150);
DISPLAY 0.872340 (-10475 2150);
PAINT AQUA (-10475 2150);
DISPLAY INVISIBLE (-10475 2150);
FORCEPROP 1 LAST COMMENT_BODY TRUE
J 2
(-10250 2200);
DISPLAY 1.170213 (-10250 2200);
PAINT GREEN (-10250 2200);
DISPLAY INVISIBLE (-10250 2200);
FORCEPROP 2 LAST PATH I60
J 0
(-9825 2325);
DISPLAY 1.021277 (-9825 2325);
DISPLAY INVISIBLE (-9825 2325);
FORCEADD OFFPAGE..5
R 2
(-10150 2575);
FORCEPROP 2 LAST $XR1 265 
J 0
(-9841 2575);
DISPLAY 0.638298 (-9841 2575);
PAINT MONO (-9841 2575);
FORCEPROP 2 LAST $XR0 264 
J 0
(-9961 2575);
DISPLAY 0.638298 (-9961 2575);
PAINT MONO (-9961 2575);
FORCEPROP 2 LAST CDS_LIB standard
J 0
(-10150 2575);
DISPLAY INVISIBLE (-10150 2575);
FORCEPROP 1 LAST OFFPAGE TRUE
J 2
(-10475 2450);
DISPLAY 0.872340 (-10475 2450);
PAINT AQUA (-10475 2450);
DISPLAY INVISIBLE (-10475 2450);
FORCEPROP 1 LAST COMMENT_BODY TRUE
J 2
(-10250 2500);
DISPLAY 1.170213 (-10250 2500);
PAINT GREEN (-10250 2500);
DISPLAY INVISIBLE (-10250 2500);
FORCEPROP 2 LAST PATH I61
J 0
(-9825 2625);
DISPLAY 1.021277 (-9825 2625);
DISPLAY INVISIBLE (-9825 2625);
FORCEADD OFFPAGE..5
R 2
(-10150 2475);
FORCEPROP 2 LAST $XR1 265 
J 0
(-9841 2475);
DISPLAY 0.638298 (-9841 2475);
PAINT MONO (-9841 2475);
FORCEPROP 2 LAST $XR0 264 
J 0
(-9961 2475);
DISPLAY 0.638298 (-9961 2475);
PAINT MONO (-9961 2475);
FORCEPROP 2 LAST CDS_LIB standard
J 0
(-10150 2475);
DISPLAY INVISIBLE (-10150 2475);
FORCEPROP 1 LAST OFFPAGE TRUE
J 2
(-10475 2350);
DISPLAY 0.872340 (-10475 2350);
PAINT AQUA (-10475 2350);
DISPLAY INVISIBLE (-10475 2350);
FORCEPROP 1 LAST COMMENT_BODY TRUE
J 2
(-10250 2400);
DISPLAY 1.170213 (-10250 2400);
PAINT GREEN (-10250 2400);
DISPLAY INVISIBLE (-10250 2400);
FORCEPROP 2 LAST PATH I62
J 0
(-9825 2525);
DISPLAY 1.021277 (-9825 2525);
DISPLAY INVISIBLE (-9825 2525);
FORCEADD Q_RES..2
(-9975 1900);
FORCEPROP 1 LAST LOCATION R3933
J 0
(-9930 2025);
DISPLAY 0.723404 (-9930 2025);
PAINT AQUA (-9930 2025);
FORCEPROP 0 LAST $SEC 1
J 0
(-9925 2075);
DISPLAY 0.680851 (-9925 2075);
PAINT MONO (-9925 2075);
DISPLAY INVISIBLE (-9925 2075);
FORCEPROP 0 LAST CDS_SEC 1
J 0
(-9925 2075);
DISPLAY 1.021277 (-9925 2075);
DISPLAY INVISIBLE (-9925 2075);
FORCEPROP 1 LASTPIN (-9975 2000) $PN 1
J 0
(-9970 1962);
DISPLAY 0.787234 (-9970 1962);
PAINT MONO (-9970 1962);
FORCEPROP 1 LASTPIN (-9975 1800) $PN 2
J 0
(-9970 1810);
DISPLAY 0.787234 (-9970 1810);
PAINT MONO (-9970 1810);
FORCEPROP 1 LAST VALUE 16.9K
J 0
(-9930 1975);
DISPLAY 0.723404 (-9930 1975);
PAINT SKYBLUE (-9930 1975);
FORCEPROP 1 LAST PACK_TYPE 0402LF
J 0
(-9935 1725);
DISPLAY 0.723404 (-9935 1725);
PAINT SKYBLUE (-9935 1725);
FORCEPROP 1 LAST MATERIAL CHIP
J 0
(-9935 1825);
DISPLAY 0.723404 (-9935 1825);
PAINT SKYBLUE (-9935 1825);
FORCEPROP 1 LAST TOLERANCE 1%
J 0
(-9930 1925);
DISPLAY 0.723404 (-9930 1925);
PAINT SKYBLUE (-9930 1925);
FORCEPROP 1 LAST WATTAGE 1/16W
J 0
(-9935 1875);
DISPLAY 0.723404 (-9935 1875);
PAINT SKYBLUE (-9935 1875);
FORCEPROP 0 LAST ROOM HSC BOM1
J 0
(-9925 2075);
DISPLAY 0.680851 (-9925 2075);
FORCEPROP 2 LAST CDS_LIB pure_quanta
J 0
(-9975 1900);
DISPLAY INVISIBLE (-9975 1900);
FORCEPROP 1 LAST PATH I63
J 0
(-9925 2075);
DISPLAY 0.978723 (-9925 2075);
PAINT WHITE (-9925 2075);
DISPLAY INVISIBLE (-9925 2075);
FORCEPROP 1 LAST PART_NUMBER CS31692FB03
J 0
(-9935 1775);
DISPLAY 0.723404 (-9935 1775);
PAINT WHITE (-9935 1775);
DISPLAY INVISIBLE (-9935 1775);
FORCEADD UNIVERSAL_POWER..1
(-9975 2100);
FORCEPROP 3 LASTPIN (-9975 2050) SIG_NAME P12V_AUX\g
J 0
(-9965 2060);
DISPLAY 0.659574 (-9965 2060);
PAINT MONO (-9965 2060);
DISPLAY INVISIBLE (-9965 2060);
FORCEPROP 1 LAST HDL_POWER P12V_AUX
J 1
(-9975 2150);
DISPLAY 0.723404 (-9975 2150);
PAINT GREEN (-9975 2150);
FORCEPROP 2 LAST CDS_LIB pure_quanta_power
J 0
(-9975 2100);
DISPLAY INVISIBLE (-9975 2100);
FORCEPROP 2 LAST BOM_COST MIO_VRD_SB
J 0
(-9975 2200);
DISPLAY 0.617021 (-9975 2200);
PAINT PURPLE (-9975 2200);
DISPLAY INVISIBLE (-9975 2200);
FORCEPROP 1 LAST PATH I64
J 0
(-9925 2125);
DISPLAY 0.872340 (-9925 2125);
PAINT AQUA (-9925 2125);
DISPLAY INVISIBLE (-9925 2125);
FORCEADD Q_RES..1
(-10150 2975);
FORCEPROP 1 LAST LOCATION PR1131
J 0
(-10425 3000);
DISPLAY 0.723404 (-10425 3000);
PAINT AQUA (-10425 3000);
FORCEPROP 0 LAST $SEC 1
J 0
(-10100 3050);
DISPLAY 0.680851 (-10100 3050);
PAINT MONO (-10100 3050);
DISPLAY INVISIBLE (-10100 3050);
FORCEPROP 0 LAST CDS_SEC 1
J 0
(-10100 3050);
DISPLAY 1.021277 (-10100 3050);
DISPLAY INVISIBLE (-10100 3050);
FORCEPROP 1 LASTPIN (-10250 2975) $PN 1
J 0
(-10238 2987);
DISPLAY 0.787234 (-10238 2987);
PAINT MONO (-10238 2987);
FORCEPROP 1 LASTPIN (-10050 2975) $PN 2
J 0
(-10088 2987);
DISPLAY 0.787234 (-10088 2987);
PAINT MONO (-10088 2987);
FORCEPROP 1 LAST MATERIAL CHIP
J 0
(-10200 2875);
DISPLAY 0.723404 (-10200 2875);
PAINT SKYBLUE (-10200 2875);
FORCEPROP 1 LAST PACK_TYPE 0402LF
J 0
(-9975 2875);
DISPLAY 0.723404 (-9975 2875);
PAINT SKYBLUE (-9975 2875);
FORCEPROP 0 LAST ROOM HSC BOM1
J 0
(-10200 2825);
DISPLAY 0.553191 (-10200 2825);
FORCEPROP 1 LAST WATTAGE 1/16W
J 2
(-10225 2875);
DISPLAY 0.723404 (-10225 2875);
PAINT SKYBLUE (-10225 2875);
FORCEPROP 1 LAST TOLERANCE 0.1%
J 0
(-10050 2925);
DISPLAY 0.723404 (-10050 2925);
PAINT SKYBLUE (-10050 2925);
FORCEPROP 1 LAST VALUE 2K
J 2
(-10200 2925);
DISPLAY 0.723404 (-10200 2925);
PAINT SKYBLUE (-10200 2925);
FORCEPROP 2 LAST CDS_LIB pure_quanta
J 0
(-10150 2975);
DISPLAY INVISIBLE (-10150 2975);
FORCEPROP 1 LAST PATH I65
J 0
(-10200 3125);
DISPLAY 0.978723 (-10200 3125);
PAINT WHITE (-10200 3125);
DISPLAY INVISIBLE (-10200 3125);
FORCEPROP 1 LAST PART_NUMBER CS22002BB07
J 0
(-10025 3000);
DISPLAY 0.723404 (-10025 3000);
PAINT WHITE (-10025 3000);
DISPLAY INVISIBLE (-10025 3000);
FORCEADD UNIVERSAL_GND..1
(-9625 2875);
FORCEPROP 3 LASTPIN (-9625 2925) SIG_NAME AGND_HSC\g
J 0
(-9615 2935);
DISPLAY 0.659574 (-9615 2935);
PAINT MONO (-9615 2935);
DISPLAY INVISIBLE (-9615 2935);
FORCEPROP 1 LAST HDL_POWER AGND_HSC
J 1
(-9600 2800);
DISPLAY 0.723404 (-9600 2800);
PAINT GREEN (-9600 2800);
FORCEPROP 2 LAST CDS_LIB pure_quanta_power
J 0
(-9625 2875);
DISPLAY INVISIBLE (-9625 2875);
FORCEPROP 1 LAST PATH I66
J 0
(-9550 2875);
DISPLAY 0.872340 (-9550 2875);
PAINT AQUA (-9550 2875);
DISPLAY INVISIBLE (-9550 2875);
FORCEADD OFFPAGE..4
(-9800 3275);
FORCEPROP 2 LAST $XR1 265 
J 0
(-9494 3275);
DISPLAY 0.638298 (-9494 3275);
PAINT MONO (-9494 3275);
FORCEPROP 2 LAST $XR0 264 
J 0
(-9614 3275);
DISPLAY 0.638298 (-9614 3275);
PAINT MONO (-9614 3275);
FORCEPROP 2 LAST CDS_LIB standard
J 0
(-9800 3275);
DISPLAY INVISIBLE (-9800 3275);
FORCEPROP 1 LAST OFFPAGE TRUE
J 0
(-9475 3150);
DISPLAY 0.872340 (-9475 3150);
PAINT GREEN (-9475 3150);
DISPLAY INVISIBLE (-9475 3150);
FORCEPROP 1 LAST COMMENT_BODY TRUE
J 0
(-9825 3175);
DISPLAY 0.872340 (-9825 3175);
PAINT GREEN (-9825 3175);
DISPLAY INVISIBLE (-9825 3175);
FORCEPROP 2 LAST PATH I67
J 0
(-9475 3325);
DISPLAY 1.021277 (-9475 3325);
DISPLAY INVISIBLE (-9475 3325);
FORCEADD OFFPAGE..4
(-9800 3475);
FORCEPROP 2 LAST $XR1 265 
J 0
(-9494 3475);
DISPLAY 0.638298 (-9494 3475);
PAINT MONO (-9494 3475);
FORCEPROP 2 LAST $XR0 264 
J 0
(-9614 3475);
DISPLAY 0.638298 (-9614 3475);
PAINT MONO (-9614 3475);
FORCEPROP 2 LAST CDS_LIB standard
J 0
(-9800 3475);
DISPLAY INVISIBLE (-9800 3475);
FORCEPROP 1 LAST OFFPAGE TRUE
J 0
(-9475 3350);
DISPLAY 0.872340 (-9475 3350);
PAINT GREEN (-9475 3350);
DISPLAY INVISIBLE (-9475 3350);
FORCEPROP 1 LAST COMMENT_BODY TRUE
J 0
(-9825 3375);
DISPLAY 0.872340 (-9825 3375);
PAINT GREEN (-9825 3375);
DISPLAY INVISIBLE (-9825 3375);
FORCEPROP 2 LAST PATH I68
J 0
(-9475 3525);
DISPLAY 1.021277 (-9475 3525);
DISPLAY INVISIBLE (-9475 3525);
FORCEADD UNIVERSAL_GND..1
(-9775 3675);
FORCEPROP 3 LASTPIN (-9775 3725) SIG_NAME AGND_HSC\g
J 0
(-9765 3735);
DISPLAY 0.659574 (-9765 3735);
PAINT MONO (-9765 3735);
DISPLAY INVISIBLE (-9765 3735);
FORCEPROP 1 LAST HDL_POWER AGND_HSC
J 1
(-9750 3600);
DISPLAY 0.723404 (-9750 3600);
PAINT GREEN (-9750 3600);
FORCEPROP 2 LAST CDS_LIB pure_quanta_power
J 0
(-9775 3675);
DISPLAY INVISIBLE (-9775 3675);
FORCEPROP 1 LAST PATH I69
J 0
(-9700 3675);
DISPLAY 0.872340 (-9700 3675);
PAINT AQUA (-9700 3675);
DISPLAY INVISIBLE (-9700 3675);
FORCEADD Q_RES..2
(-10250 3975);
FORCEPROP 1 LAST LOCATION PR3932
J 0
(-10205 4100);
DISPLAY 0.978723 (-10205 4100);
FORCEPROP 0 LAST $SEC 1
J 0
(-10200 4150);
DISPLAY 0.680851 (-10200 4150);
PAINT MONO (-10200 4150);
DISPLAY INVISIBLE (-10200 4150);
FORCEPROP 0 LAST CDS_SEC 1
J 0
(-10200 4150);
DISPLAY 1.021277 (-10200 4150);
DISPLAY INVISIBLE (-10200 4150);
FORCEPROP 1 LASTPIN (-10250 4075) $PN 1
J 0
(-10245 4037);
DISPLAY 0.787234 (-10245 4037);
PAINT MONO (-10245 4037);
FORCEPROP 1 LASTPIN (-10250 3875) $PN 2
J 0
(-10245 3885);
DISPLAY 0.787234 (-10245 3885);
PAINT MONO (-10245 3885);
FORCEPROP 1 LAST VALUE 4.99K
J 0
(-10205 4050);
DISPLAY 0.638298 (-10205 4050);
FORCEPROP 1 LAST TOLERANCE 0.1%
J 0
(-10205 4000);
DISPLAY 0.638298 (-10205 4000);
FORCEPROP 1 LAST WATTAGE 1/16W
J 0
(-10210 3950);
DISPLAY 0.638298 (-10210 3950);
FORCEPROP 1 LAST MATERIAL CHIP
J 0
(-10210 3900);
DISPLAY 0.638298 (-10210 3900);
FORCEPROP 1 LAST PACK_TYPE 0402LF
J 0
(-10210 3800);
DISPLAY 0.638298 (-10210 3800);
FORCEPROP 0 LAST ROOM HSC BOM1
J 0
(-10200 4150);
DISPLAY 0.680851 (-10200 4150);
FORCEPROP 2 LAST CDS_LIB pure_quanta
J 0
(-10250 3975);
DISPLAY INVISIBLE (-10250 3975);
FORCEPROP 1 LAST PATH I70
J 0
(-10200 4150);
DISPLAY 0.978723 (-10200 4150);
PAINT WHITE (-10200 4150);
DISPLAY INVISIBLE (-10200 4150);
FORCEPROP 1 LAST PART_NUMBER CS24992BB04
J 0
(-10210 3850);
DISPLAY 0.638298 (-10210 3850);
DISPLAY INVISIBLE (-10210 3850);
FORCEADD Q_RES..2
(-10325 4425);
FORCEPROP 1 LAST LOCATION PR3931
J 0
(-10280 4550);
DISPLAY 0.978723 (-10280 4550);
FORCEPROP 0 LAST $SEC 1
J 0
(-10275 4600);
DISPLAY 0.680851 (-10275 4600);
PAINT MONO (-10275 4600);
DISPLAY INVISIBLE (-10275 4600);
FORCEPROP 0 LAST CDS_SEC 1
J 0
(-10275 4600);
DISPLAY 1.021277 (-10275 4600);
DISPLAY INVISIBLE (-10275 4600);
FORCEPROP 1 LASTPIN (-10325 4525) $PN 1
J 0
(-10320 4487);
DISPLAY 0.787234 (-10320 4487);
PAINT MONO (-10320 4487);
FORCEPROP 1 LASTPIN (-10325 4325) $PN 2
J 0
(-10320 4335);
DISPLAY 0.787234 (-10320 4335);
PAINT MONO (-10320 4335);
FORCEPROP 1 LAST PACK_TYPE 0402LF
J 0
(-10285 4250);
DISPLAY 0.787234 (-10285 4250);
FORCEPROP 1 LAST MATERIAL CHIP
J 0
(-10285 4350);
DISPLAY 0.787234 (-10285 4350);
FORCEPROP 1 LAST WATTAGE 1/16W
J 0
(-10285 4400);
DISPLAY 0.787234 (-10285 4400);
FORCEPROP 1 LAST TOLERANCE 0.1%
J 0
(-10280 4450);
DISPLAY 0.787234 (-10280 4450);
FORCEPROP 1 LAST VALUE 75K
J 0
(-10280 4500);
DISPLAY 0.787234 (-10280 4500);
FORCEPROP 0 LAST ROOM HSC BOM1
J 0
(-10275 4600);
DISPLAY 0.680851 (-10275 4600);
FORCEPROP 2 LAST CDS_LIB pure_quanta
J 0
(-10325 4425);
DISPLAY INVISIBLE (-10325 4425);
FORCEPROP 1 LAST PATH I71
J 0
(-10275 4600);
DISPLAY 0.978723 (-10275 4600);
PAINT WHITE (-10275 4600);
DISPLAY INVISIBLE (-10275 4600);
FORCEPROP 1 LAST PART_NUMBER CS37502BB01
J 0
(-10285 4300);
DISPLAY 0.787234 (-10285 4300);
DISPLAY INVISIBLE (-10285 4300);
FORCEADD Q_CAP..1
(-9775 3975);
FORCEPROP 1 LAST LOCATION PC2190
J 0
(-9700 4075);
DISPLAY 0.723404 (-9700 4075);
PAINT AQUA (-9700 4075);
FORCEPROP 0 LAST $SEC 1
J 0
(-9700 4125);
DISPLAY 0.680851 (-9700 4125);
PAINT MONO (-9700 4125);
DISPLAY INVISIBLE (-9700 4125);
FORCEPROP 0 LAST CDS_SEC 1
J 0
(-9700 4125);
DISPLAY 1.021277 (-9700 4125);
DISPLAY INVISIBLE (-9700 4125);
FORCEPROP 1 LASTPIN (-9775 4075) $PN 1
J 0
(-9765 4055);
DISPLAY 0.787234 (-9765 4055);
PAINT MONO (-9765 4055);
FORCEPROP 1 LASTPIN (-9775 3875) $PN 2
J 0
(-9765 3855);
DISPLAY 0.787234 (-9765 3855);
PAINT MONO (-9765 3855);
FORCEPROP 1 LAST VOLTAGE 50V
J 0
(-9700 3975);
DISPLAY 0.723404 (-9700 3975);
PAINT SKYBLUE (-9700 3975);
FORCEPROP 1 LAST VALUE 0.01UF
J 0
(-9700 4025);
DISPLAY 0.723404 (-9700 4025);
PAINT SKYBLUE (-9700 4025);
FORCEPROP 0 LAST ROOM HSC BOM1
J 0
(-9700 4175);
DISPLAY 0.680851 (-9700 4175);
FORCEPROP 1 LAST MATERIAL X7R
J 0
(-9700 3925);
DISPLAY 0.723404 (-9700 3925);
PAINT SKYBLUE (-9700 3925);
FORCEPROP 1 LAST PACK_TYPE C0402
J 0
(-9700 3825);
DISPLAY 0.723404 (-9700 3825);
PAINT SKYBLUE (-9700 3825);
FORCEPROP 1 LAST TOLERANCE 10%
J 0
(-9725 3925);
DISPLAY 0.978723 (-9725 3925);
PAINT SKYBLUE (-9725 3925);
DISPLAY INVISIBLE (-9725 3925);
FORCEPROP 2 LAST CDS_LIB pure_quanta
J 0
(-9775 3975);
DISPLAY INVISIBLE (-9775 3975);
FORCEPROP 1 LAST PATH I72
J 0
(-9725 4125);
DISPLAY 0.978723 (-9725 4125);
PAINT WHITE (-9725 4125);
DISPLAY INVISIBLE (-9725 4125);
FORCEPROP 1 LAST PART_NUMBER CH31006KB18
J 0
(-9700 3875);
DISPLAY 0.723404 (-9700 3875);
PAINT WHITE (-9700 3875);
DISPLAY INVISIBLE (-9700 3875);
FORCEADD OFFPAGE..5
R 2
(-9475 1700);
FORCEPROP 2 LAST $XR3 254 
J 0
(-8926 1700);
DISPLAY 0.638298 (-8926 1700);
PAINT MONO (-8926 1700);
FORCEPROP 2 LAST $XR2 243 
J 0
(-9046 1700);
DISPLAY 0.638298 (-9046 1700);
PAINT MONO (-9046 1700);
FORCEPROP 2 LAST $XR1 189 
J 0
(-9166 1700);
DISPLAY 0.638298 (-9166 1700);
PAINT MONO (-9166 1700);
FORCEPROP 2 LAST $XR0 268 
J 0
(-9286 1700);
DISPLAY 0.638298 (-9286 1700);
PAINT MONO (-9286 1700);
FORCEPROP 2 LAST CDS_LIB standard
J 0
(-9475 1700);
DISPLAY INVISIBLE (-9475 1700);
FORCEPROP 1 LAST OFFPAGE TRUE
J 2
(-9800 1575);
DISPLAY 0.872340 (-9800 1575);
PAINT AQUA (-9800 1575);
DISPLAY INVISIBLE (-9800 1575);
FORCEPROP 1 LAST COMMENT_BODY TRUE
J 2
(-9575 1625);
DISPLAY 1.170213 (-9575 1625);
PAINT GREEN (-9575 1625);
DISPLAY INVISIBLE (-9575 1625);
FORCEPROP 2 LAST PATH I73
J 0
(-9025 1750);
DISPLAY 1.021277 (-9025 1750);
DISPLAY INVISIBLE (-9025 1750);
FORCEADD UNIVERSAL_GND..1
(-9500 2000);
FORCEPROP 3 LASTPIN (-9500 2050) SIG_NAME AGND_HSC\g
J 0
(-9490 2060);
DISPLAY 0.659574 (-9490 2060);
PAINT MONO (-9490 2060);
DISPLAY INVISIBLE (-9490 2060);
FORCEPROP 1 LAST HDL_POWER AGND_HSC
J 1
(-9475 1925);
DISPLAY 0.723404 (-9475 1925);
PAINT GREEN (-9475 1925);
FORCEPROP 2 LAST CDS_LIB pure_quanta_power
J 0
(-9500 2000);
DISPLAY INVISIBLE (-9500 2000);
FORCEPROP 1 LAST PATH I74
J 0
(-9425 2000);
DISPLAY 0.872340 (-9425 2000);
PAINT AQUA (-9425 2000);
DISPLAY INVISIBLE (-9425 2000);
FORCEADD Q_CAP..1
(-9500 2175);
FORCEPROP 1 LAST LOCATION PC2191
J 0
(-9425 2250);
DISPLAY 0.723404 (-9425 2250);
PAINT AQUA (-9425 2250);
FORCEPROP 0 LAST $SEC 1
J 0
(-9425 2300);
DISPLAY 0.680851 (-9425 2300);
PAINT MONO (-9425 2300);
DISPLAY INVISIBLE (-9425 2300);
FORCEPROP 0 LAST CDS_SEC 1
J 0
(-9425 2300);
DISPLAY 1.021277 (-9425 2300);
DISPLAY INVISIBLE (-9425 2300);
FORCEPROP 1 LASTPIN (-9500 2275) $PN 1
J 0
(-9490 2255);
DISPLAY 0.787234 (-9490 2255);
PAINT MONO (-9490 2255);
FORCEPROP 1 LASTPIN (-9500 2075) $PN 2
J 0
(-9490 2055);
DISPLAY 0.787234 (-9490 2055);
PAINT MONO (-9490 2055);
FORCEPROP 0 LAST ROOM HSC BOM1
J 0
(-9425 2300);
DISPLAY 0.680851 (-9425 2300);
FORCEPROP 1 LAST VALUE 0.068UF
J 0
(-9425 2200);
DISPLAY 0.723404 (-9425 2200);
PAINT SKYBLUE (-9425 2200);
FORCEPROP 1 LAST VOLTAGE 16V
J 0
(-9425 2150);
DISPLAY 0.723404 (-9425 2150);
PAINT SKYBLUE (-9425 2150);
FORCEPROP 1 LAST MATERIAL X7R
J 0
(-9425 2100);
DISPLAY 0.723404 (-9425 2100);
PAINT SKYBLUE (-9425 2100);
FORCEPROP 1 LAST PACK_TYPE 0402
J 0
(-9425 2000);
DISPLAY 0.723404 (-9425 2000);
PAINT SKYBLUE (-9425 2000);
FORCEPROP 2 LAST CDS_LIB pure_quanta
J 0
(-9500 2175);
DISPLAY INVISIBLE (-9500 2175);
FORCEPROP 1 LAST TOLERANCE 10%
J 0
(-9450 2125);
DISPLAY 0.978723 (-9450 2125);
PAINT SKYBLUE (-9450 2125);
DISPLAY INVISIBLE (-9450 2125);
FORCEPROP 1 LAST PATH I75
J 0
(-9450 2325);
DISPLAY 0.978723 (-9450 2325);
PAINT WHITE (-9450 2325);
DISPLAY INVISIBLE (-9450 2325);
FORCEPROP 1 LAST PART_NUMBER CH3683K1B09
J 0
(-9425 2050);
DISPLAY 0.723404 (-9425 2050);
PAINT WHITE (-9425 2050);
DISPLAY INVISIBLE (-9425 2050);
FORCEADD OFFPAGE..5
R 2
(-9375 2375);
FORCEPROP 2 LAST $XR1 265 
J 0
(-9066 2375);
DISPLAY 0.638298 (-9066 2375);
PAINT MONO (-9066 2375);
FORCEPROP 2 LAST $XR0 264 
J 0
(-9186 2375);
DISPLAY 0.638298 (-9186 2375);
PAINT MONO (-9186 2375);
FORCEPROP 2 LAST CDS_LIB standard
J 0
(-9375 2375);
DISPLAY INVISIBLE (-9375 2375);
FORCEPROP 1 LAST OFFPAGE TRUE
J 2
(-9700 2250);
DISPLAY 0.872340 (-9700 2250);
PAINT AQUA (-9700 2250);
DISPLAY INVISIBLE (-9700 2250);
FORCEPROP 1 LAST COMMENT_BODY TRUE
J 2
(-9475 2300);
DISPLAY 1.170213 (-9475 2300);
PAINT GREEN (-9475 2300);
DISPLAY INVISIBLE (-9475 2300);
FORCEPROP 2 LAST PATH I76
J 0
(-9050 2425);
DISPLAY 1.021277 (-9050 2425);
DISPLAY INVISIBLE (-9050 2425);
FORCEADD UNIVERSAL_GND..1
(-8625 2100);
FORCEPROP 3 LASTPIN (-8625 2150) SIG_NAME AGND_HSC\g
J 0
(-8615 2160);
DISPLAY 0.659574 (-8615 2160);
PAINT MONO (-8615 2160);
DISPLAY INVISIBLE (-8615 2160);
FORCEPROP 1 LAST HDL_POWER AGND_HSC
J 1
(-8600 2025);
DISPLAY 0.723404 (-8600 2025);
PAINT GREEN (-8600 2025);
FORCEPROP 2 LAST CDS_LIB pure_quanta_power
J 0
(-8625 2100);
DISPLAY INVISIBLE (-8625 2100);
FORCEPROP 1 LAST PATH I77
J 0
(-8550 2100);
DISPLAY 0.872340 (-8550 2100);
PAINT AQUA (-8550 2100);
DISPLAY INVISIBLE (-8550 2100);
FORCEADD Q_CAP..1
(-8925 2425);
FORCEPROP 1 LAST LOCATION PC2192
J 0
(-8850 2575);
DISPLAY 0.723404 (-8850 2575);
PAINT AQUA (-8850 2575);
FORCEPROP 0 LAST $SEC 1
J 0
(-8850 2625);
DISPLAY 0.680851 (-8850 2625);
PAINT MONO (-8850 2625);
DISPLAY INVISIBLE (-8850 2625);
FORCEPROP 0 LAST CDS_SEC 1
J 0
(-8850 2625);
DISPLAY 1.021277 (-8850 2625);
DISPLAY INVISIBLE (-8850 2625);
FORCEPROP 1 LASTPIN (-8925 2525) $PN 1
J 0
(-8915 2505);
DISPLAY 0.787234 (-8915 2505);
PAINT MONO (-8915 2505);
FORCEPROP 1 LASTPIN (-8925 2325) $PN 2
J 0
(-8915 2305);
DISPLAY 0.787234 (-8915 2305);
PAINT MONO (-8915 2305);
FORCEPROP 1 LAST PACK_TYPE C0402
J 0
(-8850 2325);
DISPLAY 0.723404 (-8850 2325);
PAINT SKYBLUE (-8850 2325);
FORCEPROP 1 LAST VOLTAGE 50V
J 0
(-8850 2475);
DISPLAY 0.723404 (-8850 2475);
PAINT SKYBLUE (-8850 2475);
FORCEPROP 1 LAST MATERIAL X7R
J 0
(-8850 2425);
DISPLAY 0.723404 (-8850 2425);
PAINT SKYBLUE (-8850 2425);
FORCEPROP 1 LAST VALUE 0.001UF
J 0
(-8850 2525);
DISPLAY 0.723404 (-8850 2525);
PAINT SKYBLUE (-8850 2525);
FORCEPROP 0 LAST ROOM HSC BOM1
J 0
(-8850 2275);
DISPLAY 0.680851 (-8850 2275);
FORCEPROP 2 LAST CDS_LIB pure_quanta
J 0
(-8925 2425);
DISPLAY INVISIBLE (-8925 2425);
FORCEPROP 1 LAST TOLERANCE 10%
J 0
(-8875 2375);
DISPLAY 0.978723 (-8875 2375);
PAINT SKYBLUE (-8875 2375);
DISPLAY INVISIBLE (-8875 2375);
FORCEPROP 1 LAST PATH I78
J 0
(-8875 2575);
DISPLAY 0.978723 (-8875 2575);
PAINT WHITE (-8875 2575);
DISPLAY INVISIBLE (-8875 2575);
FORCEPROP 1 LAST PART_NUMBER CH30106KB19
J 0
(-8850 2375);
DISPLAY 0.723404 (-8850 2375);
PAINT WHITE (-8850 2375);
DISPLAY INVISIBLE (-8850 2375);
FORCEADD Q_RES..1
(-8950 3575);
FORCEPROP 1 LAST LOCATION R2588
J 0
(-9225 3600);
DISPLAY 0.723404 (-9225 3600);
PAINT AQUA (-9225 3600);
FORCEPROP 0 LAST $SEC 1
J 0
(-8900 3650);
DISPLAY 0.680851 (-8900 3650);
PAINT MONO (-8900 3650);
DISPLAY INVISIBLE (-8900 3650);
FORCEPROP 0 LAST CDS_SEC 1
J 0
(-8900 3650);
DISPLAY 1.021277 (-8900 3650);
DISPLAY INVISIBLE (-8900 3650);
FORCEPROP 1 LASTPIN (-9050 3575) $PN 1
J 0
(-9038 3587);
DISPLAY 0.787234 (-9038 3587);
PAINT MONO (-9038 3587);
FORCEPROP 1 LASTPIN (-8850 3575) $PN 2
J 0
(-8888 3587);
DISPLAY 0.787234 (-8888 3587);
PAINT MONO (-8888 3587);
FORCEPROP 0 LAST ROOM HSC BOM1
J 0
(-9050 3625);
DISPLAY 0.553191 (-9050 3625);
FORCEPROP 1 LAST PACK_TYPE 0402LF
J 0
(-8775 3475);
DISPLAY 0.723404 (-8775 3475);
PAINT SKYBLUE (-8775 3475);
FORCEPROP 1 LAST WATTAGE 1/16W
J 2
(-9000 3475);
DISPLAY 0.723404 (-9000 3475);
PAINT SKYBLUE (-9000 3475);
FORCEPROP 1 LAST MATERIAL CHIP
J 0
(-8975 3475);
DISPLAY 0.723404 (-8975 3475);
PAINT SKYBLUE (-8975 3475);
FORCEPROP 1 LAST TOLERANCE 1%
J 0
(-8850 3525);
DISPLAY 0.723404 (-8850 3525);
PAINT SKYBLUE (-8850 3525);
FORCEPROP 1 LAST VALUE 22
J 2
(-9025 3525);
DISPLAY 0.723404 (-9025 3525);
PAINT SKYBLUE (-9025 3525);
FORCEPROP 2 LAST CDS_LIB pure_quanta
J 0
(-8950 3575);
DISPLAY INVISIBLE (-8950 3575);
FORCEPROP 1 LAST PATH I79
J 0
(-9000 3725);
DISPLAY 0.978723 (-9000 3725);
PAINT WHITE (-9000 3725);
DISPLAY INVISIBLE (-9000 3725);
FORCEPROP 1 LAST PART_NUMBER CS02202FB02
J 0
(-8825 3600);
DISPLAY 0.723404 (-8825 3600);
PAINT WHITE (-8825 3600);
DISPLAY INVISIBLE (-8825 3600);
FORCEADD Q_RES..1
(-8950 3400);
FORCEPROP 1 LAST LOCATION R3934
J 0
(-9225 3425);
DISPLAY 0.723404 (-9225 3425);
PAINT AQUA (-9225 3425);
FORCEPROP 0 LAST $SEC 1
J 0
(-8900 3475);
DISPLAY 0.680851 (-8900 3475);
PAINT MONO (-8900 3475);
DISPLAY INVISIBLE (-8900 3475);
FORCEPROP 0 LAST CDS_SEC 1
J 0
(-8900 3475);
DISPLAY 1.021277 (-8900 3475);
DISPLAY INVISIBLE (-8900 3475);
FORCEPROP 1 LASTPIN (-9050 3400) $PN 1
J 0
(-9038 3412);
DISPLAY 0.787234 (-9038 3412);
PAINT MONO (-9038 3412);
FORCEPROP 1 LASTPIN (-8850 3400) $PN 2
J 0
(-8888 3412);
DISPLAY 0.787234 (-8888 3412);
PAINT MONO (-8888 3412);
FORCEPROP 1 LAST TOLERANCE 1%
J 0
(-8850 3350);
DISPLAY 0.723404 (-8850 3350);
PAINT SKYBLUE (-8850 3350);
FORCEPROP 1 LAST PACK_TYPE 0402LF
J 0
(-8775 3300);
DISPLAY 0.723404 (-8775 3300);
PAINT SKYBLUE (-8775 3300);
FORCEPROP 0 LAST ROOM HSC BOM1
J 0
(-9350 3350);
DISPLAY 0.553191 (-9350 3350);
FORCEPROP 1 LAST WATTAGE 1/16W
J 2
(-9000 3300);
DISPLAY 0.723404 (-9000 3300);
PAINT SKYBLUE (-9000 3300);
FORCEPROP 1 LAST MATERIAL CHIP
J 0
(-8975 3300);
DISPLAY 0.723404 (-8975 3300);
PAINT SKYBLUE (-8975 3300);
FORCEPROP 1 LAST VALUE 22
J 2
(-9025 3350);
DISPLAY 0.723404 (-9025 3350);
PAINT SKYBLUE (-9025 3350);
FORCEPROP 2 LAST CDS_LIB pure_quanta
J 0
(-8950 3400);
DISPLAY INVISIBLE (-8950 3400);
FORCEPROP 1 LAST PATH I80
J 0
(-9000 3550);
DISPLAY 0.978723 (-9000 3550);
PAINT WHITE (-9000 3550);
DISPLAY INVISIBLE (-9000 3550);
FORCEPROP 1 LAST PART_NUMBER CS02202FB02
J 0
(-8825 3425);
DISPLAY 0.723404 (-8825 3425);
PAINT WHITE (-8825 3425);
DISPLAY INVISIBLE (-8825 3425);
FORCEADD Q_RES..2
(-8450 2450);
FORCEPROP 1 LAST LOCATION PR3935
J 0
(-8395 2600);
DISPLAY 0.723404 (-8395 2600);
PAINT AQUA (-8395 2600);
FORCEPROP 0 LAST $SEC 1
J 0
(-8375 2650);
DISPLAY 0.680851 (-8375 2650);
PAINT MONO (-8375 2650);
DISPLAY INVISIBLE (-8375 2650);
FORCEPROP 0 LAST CDS_SEC 1
J 0
(-8375 2650);
DISPLAY 1.021277 (-8375 2650);
DISPLAY INVISIBLE (-8375 2650);
FORCEPROP 1 LASTPIN (-8450 2550) $PN 1
J 0
(-8445 2512);
DISPLAY 0.787234 (-8445 2512);
PAINT MONO (-8445 2512);
FORCEPROP 1 LASTPIN (-8450 2350) $PN 2
J 0
(-8445 2360);
DISPLAY 0.787234 (-8445 2360);
PAINT MONO (-8445 2360);
FORCEPROP 1 LAST WATTAGE 1/16W
J 0
(-8400 2450);
DISPLAY 0.723404 (-8400 2450);
PAINT SKYBLUE (-8400 2450);
FORCEPROP 1 LAST VALUE 10K
J 0
(-8395 2550);
DISPLAY 0.723404 (-8395 2550);
PAINT SKYBLUE (-8395 2550);
FORCEPROP 1 LAST TOLERANCE 1%
J 0
(-8395 2500);
DISPLAY 0.723404 (-8395 2500);
PAINT SKYBLUE (-8395 2500);
FORCEPROP 0 LAST ROOM HSC BOM1
J 0
(-8400 2250);
DISPLAY 0.680851 (-8400 2250);
FORCEPROP 1 LAST PACK_TYPE 0402LF
J 0
(-8400 2300);
DISPLAY 0.723404 (-8400 2300);
PAINT SKYBLUE (-8400 2300);
FORCEPROP 1 LAST MATERIAL CHIP
J 0
(-8400 2400);
DISPLAY 0.723404 (-8400 2400);
PAINT SKYBLUE (-8400 2400);
FORCEPROP 2 LAST CDS_LIB pure_quanta
J 0
(-8450 2450);
DISPLAY INVISIBLE (-8450 2450);
FORCEPROP 1 LAST PATH I81
J 0
(-8400 2625);
DISPLAY 0.978723 (-8400 2625);
PAINT WHITE (-8400 2625);
DISPLAY INVISIBLE (-8400 2625);
FORCEPROP 1 LAST PART_NUMBER CS31002FB08
J 0
(-8400 2350);
DISPLAY 0.723404 (-8400 2350);
PAINT WHITE (-8400 2350);
DISPLAY INVISIBLE (-8400 2350);
FORCEADD OFFPAGE..4
(-8300 2675);
FORCEPROP 2 LAST $XR1 265 
J 0
(-7994 2675);
DISPLAY 0.638298 (-7994 2675);
PAINT MONO (-7994 2675);
FORCEPROP 2 LAST $XR0 264 
J 0
(-8114 2675);
DISPLAY 0.638298 (-8114 2675);
PAINT MONO (-8114 2675);
FORCEPROP 2 LAST CDS_LIB standard
J 2
(-8300 2675);
DISPLAY INVISIBLE (-8300 2675);
FORCEPROP 1 LAST OFFPAGE TRUE
J 0
(-7975 2550);
DISPLAY 0.872340 (-7975 2550);
PAINT GREEN (-7975 2550);
DISPLAY INVISIBLE (-7975 2550);
FORCEPROP 1 LAST COMMENT_BODY TRUE
J 0
(-8325 2575);
DISPLAY 0.872340 (-8325 2575);
PAINT GREEN (-8325 2575);
DISPLAY INVISIBLE (-8325 2575);
FORCEPROP 2 LAST PATH I82
J 0
(-7975 2725);
DISPLAY 1.021277 (-7975 2725);
DISPLAY INVISIBLE (-7975 2725);
FORCEADD UNIVERSAL_GND..1
(-7625 2600);
FORCEPROP 3 LASTPIN (-7625 2650) SIG_NAME AGND_HSC\g
J 0
(-7615 2660);
DISPLAY 0.659574 (-7615 2660);
PAINT MONO (-7615 2660);
DISPLAY INVISIBLE (-7615 2660);
FORCEPROP 1 LAST HDL_POWER AGND_HSC
J 1
(-7600 2525);
DISPLAY 0.723404 (-7600 2525);
PAINT GREEN (-7600 2525);
FORCEPROP 2 LAST CDS_LIB pure_quanta_power
J 0
(-7625 2600);
DISPLAY INVISIBLE (-7625 2600);
FORCEPROP 1 LAST PATH I83
J 0
(-7550 2600);
DISPLAY 0.872340 (-7550 2600);
PAINT AQUA (-7550 2600);
DISPLAY INVISIBLE (-7550 2600);
FORCEADD Q_CAP..1
(-8100 2850);
FORCEPROP 1 LAST LOCATION PC2193
J 0
(-8025 3000);
DISPLAY 0.723404 (-8025 3000);
PAINT AQUA (-8025 3000);
FORCEPROP 0 LAST $SEC 1
J 0
(-8025 3050);
DISPLAY 0.680851 (-8025 3050);
PAINT MONO (-8025 3050);
DISPLAY INVISIBLE (-8025 3050);
FORCEPROP 0 LAST CDS_SEC 1
J 0
(-8025 3050);
DISPLAY 1.021277 (-8025 3050);
DISPLAY INVISIBLE (-8025 3050);
FORCEPROP 1 LASTPIN (-8100 2950) $PN 1
J 0
(-8090 2930);
DISPLAY 0.787234 (-8090 2930);
PAINT MONO (-8090 2930);
FORCEPROP 1 LASTPIN (-8100 2750) $PN 2
J 0
(-8090 2730);
DISPLAY 0.787234 (-8090 2730);
PAINT MONO (-8090 2730);
FORCEPROP 1 LAST PACK_TYPE C0402
J 0
(-8025 2750);
DISPLAY 0.723404 (-8025 2750);
PAINT SKYBLUE (-8025 2750);
FORCEPROP 1 LAST VOLTAGE 25V
J 0
(-8025 2900);
DISPLAY 0.723404 (-8025 2900);
PAINT SKYBLUE (-8025 2900);
FORCEPROP 1 LAST VALUE 0.047UF
J 0
(-8025 2950);
DISPLAY 0.723404 (-8025 2950);
PAINT SKYBLUE (-8025 2950);
FORCEPROP 0 LAST ROOM HSC BOM1
J 0
(-8325 2900);
DISPLAY 0.553191 (-8325 2900);
FORCEPROP 1 LAST MATERIAL X7R
J 0
(-8025 2850);
DISPLAY 0.723404 (-8025 2850);
PAINT SKYBLUE (-8025 2850);
FORCEPROP 1 LAST TOLERANCE 10%
J 0
(-8050 2800);
DISPLAY 0.978723 (-8050 2800);
PAINT SKYBLUE (-8050 2800);
DISPLAY INVISIBLE (-8050 2800);
FORCEPROP 2 LAST CDS_LIB pure_quanta
J 0
(-8100 2850);
DISPLAY INVISIBLE (-8100 2850);
FORCEPROP 1 LAST PATH I84
J 0
(-8050 3000);
DISPLAY 0.978723 (-8050 3000);
PAINT WHITE (-8050 3000);
DISPLAY INVISIBLE (-8050 3000);
FORCEPROP 1 LAST PART_NUMBER CH3474K1B04
J 0
(-8025 2800);
DISPLAY 0.723404 (-8025 2800);
PAINT WHITE (-8025 2800);
DISPLAY INVISIBLE (-8025 2800);
FORCEADD Q_RES..1
(-8125 3275);
FORCEPROP 1 LAST LOCATION PR3937
J 0
(-8425 3300);
DISPLAY 0.723404 (-8425 3300);
PAINT AQUA (-8425 3300);
FORCEPROP 0 LAST $SEC 1
J 0
(-8075 3350);
DISPLAY 0.680851 (-8075 3350);
PAINT MONO (-8075 3350);
DISPLAY INVISIBLE (-8075 3350);
FORCEPROP 0 LAST CDS_SEC 1
J 0
(-8075 3350);
DISPLAY 1.021277 (-8075 3350);
DISPLAY INVISIBLE (-8075 3350);
FORCEPROP 1 LASTPIN (-8225 3275) $PN 1
J 0
(-8213 3287);
DISPLAY 0.787234 (-8213 3287);
PAINT MONO (-8213 3287);
FORCEPROP 1 LASTPIN (-8025 3275) $PN 2
J 0
(-8063 3287);
DISPLAY 0.787234 (-8063 3287);
PAINT MONO (-8063 3287);
FORCEPROP 1 LAST PACK_TYPE 0402LF
J 0
(-7975 3175);
DISPLAY 0.723404 (-7975 3175);
PAINT SKYBLUE (-7975 3175);
FORCEPROP 1 LAST TOLERANCE 1%
J 0
(-8025 3225);
DISPLAY 0.723404 (-8025 3225);
PAINT SKYBLUE (-8025 3225);
FORCEPROP 0 LAST ROOM HSC BOM1
J 0
(-8225 3350);
DISPLAY 0.553191 (-8225 3350);
FORCEPROP 1 LAST WATTAGE 1/16W
J 2
(-8225 3175);
DISPLAY 0.723404 (-8225 3175);
PAINT SKYBLUE (-8225 3175);
FORCEPROP 1 LAST MATERIAL CHIP
J 0
(-8175 3175);
DISPLAY 0.723404 (-8175 3175);
PAINT SKYBLUE (-8175 3175);
FORCEPROP 1 LAST VALUE 120K
J 2
(-8175 3225);
DISPLAY 0.723404 (-8175 3225);
PAINT SKYBLUE (-8175 3225);
FORCEPROP 2 LAST CDS_LIB pure_quanta
J 0
(-8125 3275);
DISPLAY INVISIBLE (-8125 3275);
FORCEPROP 1 LAST PATH I85
J 0
(-8175 3425);
DISPLAY 0.978723 (-8175 3425);
PAINT WHITE (-8175 3425);
DISPLAY INVISIBLE (-8175 3425);
FORCEPROP 1 LAST PART_NUMBER CS41202FB05
J 0
(-7975 3300);
DISPLAY 0.723404 (-7975 3300);
PAINT WHITE (-7975 3300);
DISPLAY INVISIBLE (-7975 3300);
FORCEADD Q_RES..2
(-7625 2875);
FORCEPROP 1 LAST LOCATION PR1133
J 0
(-7570 3025);
DISPLAY 0.723404 (-7570 3025);
PAINT AQUA (-7570 3025);
FORCEPROP 0 LAST $SEC 1
J 0
(-7550 3075);
DISPLAY 0.680851 (-7550 3075);
PAINT MONO (-7550 3075);
DISPLAY INVISIBLE (-7550 3075);
FORCEPROP 0 LAST CDS_SEC 1
J 0
(-7550 3075);
DISPLAY 1.021277 (-7550 3075);
DISPLAY INVISIBLE (-7550 3075);
FORCEPROP 1 LASTPIN (-7625 2975) $PN 1
J 0
(-7620 2937);
DISPLAY 0.787234 (-7620 2937);
PAINT MONO (-7620 2937);
FORCEPROP 1 LASTPIN (-7625 2775) $PN 2
J 0
(-7620 2785);
DISPLAY 0.787234 (-7620 2785);
PAINT MONO (-7620 2785);
FORCEPROP 1 LAST VALUE 2K
J 0
(-7570 2975);
DISPLAY 0.723404 (-7570 2975);
PAINT SKYBLUE (-7570 2975);
FORCEPROP 1 LAST TOLERANCE 0.1%
J 0
(-7570 2925);
DISPLAY 0.723404 (-7570 2925);
PAINT SKYBLUE (-7570 2925);
FORCEPROP 0 LAST ROOM HSC BOM1
J 0
(-7575 2675);
DISPLAY 0.553191 (-7575 2675);
FORCEPROP 1 LAST PACK_TYPE 0402LF
J 0
(-7575 2725);
DISPLAY 0.723404 (-7575 2725);
PAINT SKYBLUE (-7575 2725);
FORCEPROP 1 LAST MATERIAL CHIP
J 0
(-7575 2825);
DISPLAY 0.723404 (-7575 2825);
PAINT SKYBLUE (-7575 2825);
FORCEPROP 1 LAST WATTAGE 1/16W
J 0
(-7575 2875);
DISPLAY 0.723404 (-7575 2875);
PAINT SKYBLUE (-7575 2875);
FORCEPROP 2 LAST CDS_LIB pure_quanta
J 0
(-7625 2875);
DISPLAY INVISIBLE (-7625 2875);
FORCEPROP 1 LAST PATH I86
J 0
(-7575 3050);
DISPLAY 0.978723 (-7575 3050);
PAINT WHITE (-7575 3050);
DISPLAY INVISIBLE (-7575 3050);
FORCEPROP 1 LAST PART_NUMBER CS22002BB07
J 0
(-7575 2775);
DISPLAY 0.723404 (-7575 2775);
PAINT WHITE (-7575 2775);
DISPLAY INVISIBLE (-7575 2775);
FORCEADD UNIVERSAL_GND..1
(-7550 3200);
FORCEPROP 3 LASTPIN (-7550 3250) SIG_NAME AGND_HSC\g
J 0
(-7540 3260);
DISPLAY 0.659574 (-7540 3260);
PAINT MONO (-7540 3260);
DISPLAY INVISIBLE (-7540 3260);
FORCEPROP 1 LAST HDL_POWER AGND_HSC
J 1
(-7525 3150);
DISPLAY 0.723404 (-7525 3150);
PAINT GREEN (-7525 3150);
FORCEPROP 2 LAST CDS_LIB pure_quanta_power
J 0
(-7550 3200);
DISPLAY INVISIBLE (-7550 3200);
FORCEPROP 1 LAST PATH I87
J 0
(-7475 3200);
DISPLAY 0.872340 (-7475 3200);
PAINT AQUA (-7475 3200);
DISPLAY INVISIBLE (-7475 3200);
FORCEADD GND..1
(-9175 3725);
FORCEPROP 3 LASTPIN (-9175 3775) SIG_NAME GND\g
J 0
(-9165 3785);
DISPLAY 0.659574 (-9165 3785);
PAINT MONO (-9165 3785);
DISPLAY INVISIBLE (-9165 3785);
FORCEPROP 1 LAST SIZE 1B
J 0
(-9100 3675);
DISPLAY 0.872340 (-9100 3675);
PAINT AQUA (-9100 3675);
DISPLAY INVISIBLE (-9100 3675);
FORCEPROP 2 LAST CDS_LIB pure_quanta_power
J 0
(-9175 3725);
DISPLAY INVISIBLE (-9175 3725);
FORCEPROP 1 LAST HDL_POWER GND
J 0
(-9175 3875);
DISPLAY 1.170213 (-9175 3875);
PAINT GREEN (-9175 3875);
DISPLAY INVISIBLE (-9175 3875);
FORCEPROP 1 LAST PATH I88
J 0
(-9100 3725);
DISPLAY 0.872340 (-9100 3725);
PAINT AQUA (-9100 3725);
DISPLAY INVISIBLE (-9100 3725);
FORCEADD SS15P3SM386A..1
R 1
(-9175 4225);
FORCEPROP 1 LAST LOCATION PD111
J 0
(-9075 4275);
DISPLAY 0.723404 (-9075 4275);
PAINT AQUA (-9075 4275);
FORCEPROP 0 LAST $SEC 1
R 1
J 0
(-9075 4325);
DISPLAY 0.680851 (-9075 4325);
PAINT MONO (-9075 4325);
DISPLAY INVISIBLE (-9075 4325);
FORCEPROP 0 LAST CDS_SEC 1
R 1
J 0
(-9075 4325);
DISPLAY 1.021277 (-9075 4325);
DISPLAY INVISIBLE (-9075 4325);
FORCEPROP 0 LASTPIN (-9225 3950) $PN 1
R 1
J 2
(-9235 3940);
DISPLAY 0.680851 (-9235 3940);
PAINT MONO (-9235 3940);
FORCEPROP 0 LASTPIN (-9125 3950) $PN 2
R 1
J 2
(-9135 3940);
DISPLAY 0.680851 (-9135 3940);
PAINT MONO (-9135 3940);
FORCEPROP 0 LASTPIN (-9175 4500) $PN K
R 1
J 0
(-9185 4510);
DISPLAY 0.680851 (-9185 4510);
PAINT MONO (-9185 4510);
FORCEPROP 2 LAST PART_TYPE SMLF
J 0
(-9075 4200);
DISPLAY 1.021277 (-9075 4200);
FORCEPROP 2 LAST VALUE SS15P3S-M3/86A
J 0
(-9075 4125);
DISPLAY 0.808511 (-9075 4125);
PAINT SKYBLUE (-9075 4125);
FORCEPROP 1 LAST MATERIAL IC
J 0
(-9075 4025);
DISPLAY 0.723404 (-9075 4025);
PAINT SKYBLUE (-9075 4025);
FORCEPROP 0 LAST ROOM HSC BOM1
J 0
(-9075 4375);
DISPLAY 0.680851 (-9075 4375);
FORCEPROP 2 LAST CDS_LIB pure_quanta
R 1
J 0
(-9175 4225);
DISPLAY INVISIBLE (-9175 4225);
FORCEPROP 1 LAST NEEDS_NO_SIZE TRUE
R 1
J 0
(-9175 4225);
DISPLAY 0.723404 (-9175 4225);
PAINT GREEN (-9175 4225);
DISPLAY INVISIBLE (-9175 4225);
FORCEPROP 1 LAST CDS_LMAN_SYM_OUTLINE -125,100,125,-100
R 1
J 0
(-9175 4225);
DISPLAY 0.468085 (-9175 4225);
PAINT GREEN (-9175 4225);
DISPLAY INVISIBLE (-9175 4225);
FORCEPROP 1 LAST PATH I89
R 1
J 0
(-9175 4225);
DISPLAY 0.723404 (-9175 4225);
PAINT GREEN (-9175 4225);
DISPLAY INVISIBLE (-9175 4225);
FORCEPROP 1 LAST PART_NUMBER BC015P3SZ00
J 0
(-9075 4075);
DISPLAY 0.723404 (-9075 4075);
PAINT WHITE (-9075 4075);
DISPLAY INVISIBLE (-9075 4075);
FORCEADD UNIVERSAL_POWER..1
(-8575 4800);
FORCEPROP 3 LASTPIN (-8575 4750) SIG_NAME P12V_AUX\g
J 0
(-8565 4760);
DISPLAY 0.659574 (-8565 4760);
PAINT MONO (-8565 4760);
DISPLAY INVISIBLE (-8565 4760);
FORCEPROP 1 LAST HDL_POWER P12V_AUX
J 1
(-8575 4850);
DISPLAY 0.723404 (-8575 4850);
PAINT GREEN (-8575 4850);
FORCEPROP 2 LAST BOM_COST MIO_VRD_SB
J 0
(-8575 4900);
DISPLAY 0.617021 (-8575 4900);
PAINT PURPLE (-8575 4900);
DISPLAY INVISIBLE (-8575 4900);
FORCEPROP 2 LAST CDS_LIB pure_quanta_power
J 0
(-8575 4800);
DISPLAY INVISIBLE (-8575 4800);
FORCEPROP 1 LAST PATH I90
J 0
(-8525 4825);
DISPLAY 0.872340 (-8525 4825);
PAINT AQUA (-8525 4825);
DISPLAY INVISIBLE (-8525 4825);
FORCEADD Q_RES..2
(-8425 3900);
FORCEPROP 1 LAST LOCATION R3936
J 0
(-8380 4025);
DISPLAY 0.723404 (-8380 4025);
PAINT AQUA (-8380 4025);
FORCEPROP 0 LAST $SEC 1
J 0
(-8375 4075);
DISPLAY 0.680851 (-8375 4075);
PAINT MONO (-8375 4075);
DISPLAY INVISIBLE (-8375 4075);
FORCEPROP 0 LAST CDS_SEC 1
J 0
(-8375 4075);
DISPLAY 1.021277 (-8375 4075);
DISPLAY INVISIBLE (-8375 4075);
FORCEPROP 1 LASTPIN (-8425 4000) $PN 1
J 0
(-8420 3962);
DISPLAY 0.787234 (-8420 3962);
PAINT MONO (-8420 3962);
FORCEPROP 1 LASTPIN (-8425 3800) $PN 2
J 0
(-8420 3810);
DISPLAY 0.787234 (-8420 3810);
PAINT MONO (-8420 3810);
FORCEPROP 1 LAST PACK_TYPE 0402LF
J 0
(-8385 3725);
DISPLAY 0.723404 (-8385 3725);
PAINT SKYBLUE (-8385 3725);
FORCEPROP 1 LAST MATERIAL CHIP
J 0
(-8385 3825);
DISPLAY 0.723404 (-8385 3825);
PAINT SKYBLUE (-8385 3825);
FORCEPROP 1 LAST WATTAGE 1/16W
J 0
(-8385 3875);
DISPLAY 0.723404 (-8385 3875);
PAINT SKYBLUE (-8385 3875);
FORCEPROP 1 LAST TOLERANCE 1%
J 0
(-8380 3925);
DISPLAY 0.723404 (-8380 3925);
PAINT SKYBLUE (-8380 3925);
FORCEPROP 0 LAST ROOM HSC BOM1
J 0
(-8700 3900);
DISPLAY 0.680851 (-8700 3900);
FORCEPROP 1 LAST VALUE 4.7K
J 0
(-8380 3975);
DISPLAY 0.723404 (-8380 3975);
PAINT SKYBLUE (-8380 3975);
FORCEPROP 2 LAST CDS_LIB pure_quanta
J 0
(-8425 3900);
DISPLAY INVISIBLE (-8425 3900);
FORCEPROP 1 LAST PATH I91
J 0
(-8375 4075);
DISPLAY 0.978723 (-8375 4075);
PAINT WHITE (-8375 4075);
DISPLAY INVISIBLE (-8375 4075);
FORCEPROP 1 LAST PART_NUMBER CS24702FB06
J 0
(-8385 3775);
DISPLAY 0.723404 (-8385 3775);
PAINT WHITE (-8385 3775);
DISPLAY INVISIBLE (-8385 3775);
FORCEADD UNIVERSAL_POWER..1
(-8225 4250);
FORCEPROP 3 LASTPIN (-8225 4200) SIG_NAME HSC_VDD\g
J 0
(-8215 4210);
DISPLAY 0.659574 (-8215 4210);
PAINT MONO (-8215 4210);
DISPLAY INVISIBLE (-8215 4210);
FORCEPROP 1 LAST HDL_POWER HSC_VDD
J 1
(-8225 4300);
DISPLAY 0.723404 (-8225 4300);
PAINT GREEN (-8225 4300);
FORCEPROP 2 LAST CDS_LIB pure_quanta_power
J 0
(-8225 4250);
DISPLAY INVISIBLE (-8225 4250);
FORCEPROP 2 LAST BOM_COST MIO_VRD_SB
J 0
(-8225 4350);
DISPLAY 0.617021 (-8225 4350);
PAINT PURPLE (-8225 4350);
DISPLAY INVISIBLE (-8225 4350);
FORCEPROP 1 LAST PATH I92
J 0
(-8175 4275);
DISPLAY 0.872340 (-8175 4275);
PAINT AQUA (-8175 4275);
DISPLAY INVISIBLE (-8175 4275);
FORCEADD OFFPAGE..4
(-7375 3075);
FORCEPROP 2 LAST $XR1 265 
J 0
(-7069 3075);
DISPLAY 0.638298 (-7069 3075);
PAINT MONO (-7069 3075);
FORCEPROP 2 LAST $XR0 264 
J 0
(-7189 3075);
DISPLAY 0.638298 (-7189 3075);
PAINT MONO (-7189 3075);
FORCEPROP 2 LAST CDS_LIB standard
J 0
(-7375 3075);
DISPLAY INVISIBLE (-7375 3075);
FORCEPROP 1 LAST OFFPAGE TRUE
J 0
(-7050 2950);
DISPLAY 0.872340 (-7050 2950);
PAINT GREEN (-7050 2950);
DISPLAY INVISIBLE (-7050 2950);
FORCEPROP 1 LAST COMMENT_BODY TRUE
J 0
(-7400 2975);
DISPLAY 0.872340 (-7400 2975);
PAINT GREEN (-7400 2975);
DISPLAY INVISIBLE (-7400 2975);
FORCEPROP 2 LAST PATH I94
J 0
(-7050 3125);
DISPLAY 1.021277 (-7050 3125);
DISPLAY INVISIBLE (-7050 3125);
FORCEADD OFFPAGE..5
R 2
(-7375 3400);
FORCEPROP 2 LAST $XR1 80 
J 0
(-7066 3400);
DISPLAY 0.638298 (-7066 3400);
PAINT MONO (-7066 3400);
FORCEPROP 2 LAST $XR0 268 
J 0
(-7186 3400);
DISPLAY 0.638298 (-7186 3400);
PAINT MONO (-7186 3400);
FORCEPROP 2 LAST CDS_LIB standard
J 0
(-7375 3400);
DISPLAY INVISIBLE (-7375 3400);
FORCEPROP 1 LAST OFFPAGE TRUE
J 2
(-7700 3275);
DISPLAY 0.872340 (-7700 3275);
PAINT AQUA (-7700 3275);
DISPLAY INVISIBLE (-7700 3275);
FORCEPROP 1 LAST COMMENT_BODY TRUE
J 2
(-7475 3325);
DISPLAY 1.170213 (-7475 3325);
PAINT GREEN (-7475 3325);
DISPLAY INVISIBLE (-7475 3325);
FORCEPROP 2 LAST PATH I95
J 0
(-7175 3450);
DISPLAY 1.021277 (-7175 3450);
DISPLAY INVISIBLE (-7175 3450);
FORCEADD OFFPAGE..5
R 2
(-7375 3575);
PAINT RED (-7375 3575);
FORCEPROP 2 LAST $XR1 85 
J 0
(-7066 3575);
DISPLAY 0.638298 (-7066 3575);
PAINT MONO (-7066 3575);
FORCEPROP 2 LAST $XR0 268 
J 0
(-7186 3575);
DISPLAY 0.638298 (-7186 3575);
PAINT MONO (-7186 3575);
FORCEPROP 2 LAST CDS_LIB standard
J 2
(-7375 3575);
DISPLAY INVISIBLE (-7375 3575);
FORCEPROP 1 LAST OFFPAGE TRUE
J 2
(-7700 3450);
DISPLAY 0.872340 (-7700 3450);
PAINT AQUA (-7700 3450);
DISPLAY INVISIBLE (-7700 3450);
FORCEPROP 1 LAST COMMENT_BODY TRUE
J 2
(-7475 3500);
DISPLAY 1.170213 (-7475 3500);
PAINT GREEN (-7475 3500);
DISPLAY INVISIBLE (-7475 3500);
FORCEPROP 2 LAST PATH I96
J 0
(-7175 3625);
DISPLAY 1.021277 (-7175 3625);
DISPLAY INVISIBLE (-7175 3625);
FORCEADD Q_RES..1
R 1
(-8000 3900);
FORCEPROP 1 LAST LOCATION R2587
J 0
(-7925 4050);
DISPLAY 0.723404 (-7925 4050);
PAINT AQUA (-7925 4050);
FORCEPROP 0 LAST $SEC 1
R 1
J 0
(-7925 4100);
DISPLAY 0.680851 (-7925 4100);
PAINT MONO (-7925 4100);
DISPLAY INVISIBLE (-7925 4100);
FORCEPROP 0 LAST CDS_SEC 1
R 1
J 0
(-7925 4100);
DISPLAY 0.680851 (-7925 4100);
DISPLAY INVISIBLE (-7925 4100);
FORCEPROP 1 LASTPIN (-8000 3800) $PN 1
R 1
J 0
(-8012 3812);
DISPLAY 0.787234 (-8012 3812);
PAINT MONO (-8012 3812);
FORCEPROP 1 LASTPIN (-8000 4000) $PN 2
R 1
J 0
(-8012 3962);
DISPLAY 0.787234 (-8012 3962);
PAINT MONO (-8012 3962);
FORCEPROP 1 LAST MATERIAL CHIP
J 0
(-7925 3750);
DISPLAY 0.638298 (-7925 3750);
PAINT SKYBLUE (-7925 3750);
FORCEPROP 1 LAST WATTAGE 1/16W
J 0
(-7925 3850);
DISPLAY 0.723404 (-7925 3850);
PAINT SKYBLUE (-7925 3850);
FORCEPROP 1 LAST TOLERANCE 1%
J 0
(-7925 3950);
DISPLAY 0.723404 (-7925 3950);
PAINT SKYBLUE (-7925 3950);
FORCEPROP 1 LAST VALUE 1K
J 0
(-7925 4000);
DISPLAY 0.723404 (-7925 4000);
PAINT SKYBLUE (-7925 4000);
FORCEPROP 1 LAST PACK_TYPE 0402LF
J 0
(-7925 3900);
DISPLAY 0.723404 (-7925 3900);
PAINT SKYBLUE (-7925 3900);
FORCEPROP 0 LAST ROOM HSC BOM1
J 0
(-7925 4100);
DISPLAY 0.680851 (-7925 4100);
FORCEPROP 2 LAST CDS_LIB pure_quanta
J 0
(-8000 3900);
DISPLAY INVISIBLE (-8000 3900);
FORCEPROP 1 LAST PATH I99
R 1
J 0
(-8150 3850);
DISPLAY 0.978723 (-8150 3850);
PAINT WHITE (-8150 3850);
DISPLAY INVISIBLE (-8150 3850);
FORCEPROP 1 LAST PART_NUMBER CS21002FB06
J 0
(-7925 3800);
DISPLAY 0.723404 (-7925 3800);
PAINT WHITE (-7925 3800);
DISPLAY INVISIBLE (-7925 3800);
FORCEADD QUANTA_TITLE_BLOCK_C..1
(-6900 -875);
FORCEPROP 0 LAST CDS_CON_LAST_MODIFIED Thu Sep 14 16:12:44 2023
J 0
(-8785 -860);
PAINT MONO (-8785 -860);
DISPLAY INVISIBLE (-8785 -860);
FORCEPROP 2 LAST CUSTOM_TXT_CDS <XR_PAGE_TITLE>
J 0
(-14790 4375);
DISPLAY 0.638298 (-14790 4375);
PAINT PINK (-14790 4375);
DISPLAY INVISIBLE (-14790 4375);
FORCEPROP 2 LAST CUSTOM_TXT_CDS <CON_LAST_MODIFIED>
J 0
(-8785 -860);
DISPLAY 0.978723 (-8785 -860);
FORCEPROP 2 LAST CUSTOM_TXT_CDS <CON_PAGE_NUM> OF <CON_TOTAL_PAGES>
J 0
(-7346 -857);
DISPLAY 0.978723 (-7346 -857);
FORCEPROP 2 LAST CUSTOM_TXT_CDS <Q_NUMBER>
J 0
(-8303 -772);
DISPLAY 1.212766 (-8303 -772);
FORCEPROP 2 LAST CUSTOM_TXT_CDS <Q_REV>
J 0
(-7084 -772);
DISPLAY 1.212766 (-7084 -772);
FORCEPROP 2 LAST CUSTOM_TXT_CDS <Q_PROJ>
J 0
(-9282 -773);
DISPLAY 1.212766 (-9282 -773);
FORCEPROP 1 LAST CUSTOM_TXT_CDS <NAME_2>
J 0
(-10075 -825);
FORCEPROP 1 LAST CUSTOM_TXT_CDS <NAME_1>
J 0
(-10075 -700);
FORCEPROP 1 LAST Q_TITLE HSC MP5990 (1/3)
J 0
(-16266 -849);
DISPLAY 2.446809 (-16266 -849);
PAINT GREEN (-16266 -849);
FORCEPROP 1 LAST CDS_LMAN_SYM_OUTLINE -9475,6775,100,-125
J 0
(-6900 -875);
DISPLAY 0.468085 (-6900 -875);
PAINT GREEN (-6900 -875);
DISPLAY INVISIBLE (-6900 -875);
FORCEPROP 2 LAST CDS_LIB pure_quanta
J 0
(-6900 -875);
PAINT MONO (-6900 -875);
DISPLAY INVISIBLE (-6900 -875);
FORCEPROP 2 LAST PAGE_BORDER TRUE
J 0
(-14790 4375);
DISPLAY 0.638298 (-14790 4375);
PAINT PINK (-14790 4375);
DISPLAY INVISIBLE (-14790 4375);
FORCEPROP 2 LAST CDS_XR_PAGE_TITLE CR-263 : @T6G_MB_LIB.T6G(SCH_1):PAGE263
J 0
(-14790 4375);
DISPLAY 0.638298 (-14790 4375);
PAINT PINK (-14790 4375);
DISPLAY INVISIBLE (-14790 4375);
FORCEPROP 1 LAST Q_DEPT BU9
J 1
(-10663 -826);
DISPLAY 1.957447 (-10663 -826);
PAINT GREEN (-10663 -826);
DISPLAY INVISIBLE (-10663 -826);
FORCEPROP 1 LAST COMMENT_BODY TRUE
J 0
(-6888 -888);
DISPLAY 0.978723 (-6888 -888);
PAINT GREEN (-6888 -888);
DISPLAY INVISIBLE (-6888 -888);
FORCEADD DNS..2
(-12825 2150);
PAINT RED (-12825 2150);
FORCEPROP 2 LAST CDS_LIB mstr_misc
J 0
(-12825 2150);
DISPLAY INVISIBLE (-12825 2150);
FORCEPROP 1 LAST COMMENT_BODY TRUE
R 1
J 0
(-12750 1925);
DISPLAY 0.872340 (-12750 1925);
PAINT GREEN (-12750 1925);
DISPLAY INVISIBLE (-12750 1925);
WIRE 16 -1 (-12850 1650)(-12850 1600);
WIRE 16 -1 (-9975 1300)(-9975 1350);
WIRE 16 -1 (-14225 2800)(-14225 2775);
WIRE 16 -1 (-15225 4225)(-15225 4150);
WIRE 16 -1 (-14225 4025)(-14225 4250);
WIRE 16 -1 (-13325 2075)(-13325 1925);
WIRE 16 -1 (-9975 2050)(-9975 2000);
WIRE 16 -1 (-10050 2975)(-9625 2975);
WIRE 16 -1 (-9625 2975)(-9625 2925);
WIRE 16 -1 (-9500 2075)(-9500 2050);
WIRE 16 -1 (-8025 3275)(-7550 3275);
WIRE 16 -1 (-7550 3275)(-7550 3250);
WIRE 16 -1 (-15425 3725)(-15425 3875);
WIRE 16 -1 (-15425 3875)(-15225 3875);
WIRE 16 -1 (-15225 3875)(-14925 3875);
WIRE 16 -1 (-15225 3950)(-15225 3875);
WIRE 16 -1 (-14400 3875)(-14925 3875);
WIRE 16 -1 (-14925 3700)(-14925 3875);
WIRE 16 -1 (-14400 3375)(-14400 3875);
WIRE 16 -1 (-14400 3375)(-12225 3375);
FORCEPROP 2 LAST SIG_NAME HSC_VDD_R
J 0
(-12435 3385);
DISPLAY 0.808511 (-12435 3385);
FORCEPROP 2 LASTPROP $XRERR UNIQUE?
J 0
(-12675 3385);
DISPLAY 0.638298 (-12675 3385);
PAINT MONO (-12675 3385);
DISPLAY INVISIBLE (-12675 3385);
WIRE 16 -1 (-12225 3375)(-11975 3375);
WIRE 16 -1 (-12225 3325)(-12225 3375);
WIRE 16 -1 (-12225 3325)(-11975 3325);
WIRE 16 -1 (-10825 2275)(-10200 2275);
FORCEPROP 2 LAST SIG_NAME HSC_FLT_TYPE
J 0
(-10710 2285);
DISPLAY 0.808511 (-10710 2285);
WIRE 16 -1 (-10825 2475)(-10200 2475);
FORCEPROP 2 LAST SIG_NAME HSC_SCREF
J 0
(-10710 2485);
DISPLAY 0.808511 (-10710 2485);
WIRE 16 -1 (-10825 2575)(-10200 2575);
FORCEPROP 2 LAST SIG_NAME HSC_OCREF
J 0
(-10710 2585);
DISPLAY 0.808511 (-10710 2585);
WIRE 16 -1 (-13575 3075)(-11975 3075);
FORCEPROP 2 LAST SIG_NAME SMB_SML1_PMBUS_HSC_R_SDA
J 0
(-12910 3085);
DISPLAY 0.723404 (-12910 3085);
FORCEPROP 2 LASTPROP $XRERR UNIQUE?
J 0
(-13150 3085);
DISPLAY 0.638298 (-13150 3085);
PAINT MONO (-13150 3085);
DISPLAY INVISIBLE (-13150 3085);
WIRE 16 -1 (-13575 3175)(-11975 3175);
FORCEPROP 2 LAST SIG_NAME SMB_SML1_PMBUS_HSC_L_SCL
J 0
(-12910 3185);
DISPLAY 0.723404 (-12910 3185);
FORCEPROP 2 LASTPROP $XRERR UNIQUE?
J 0
(-13150 3185);
DISPLAY 0.638298 (-13150 3185);
PAINT MONO (-13150 3185);
DISPLAY INVISIBLE (-13150 3185);
WIRE 16 -1 (-15050 3175)(-13775 3175);
FORCEPROP 2 LAST SIG_NAME SMB_SML1_PMBUS_HSC_SCL
J 0
(-15060 3185);
DISPLAY 0.723404 (-15060 3185);
WIRE 16 -1 (-13775 3075)(-15050 3075);
FORCEPROP 2 LAST SIG_NAME SMB_SML1_PMBUS_HSC_SDA
J 0
(-15060 3085);
DISPLAY 0.723404 (-15060 3085);
WIRE 16 -1 (-14725 2500)(-15750 2500);
FORCEPROP 2 LAST SIG_NAME IRQ_SML1_PMBUS_ALERT_N
J 0
(-15760 2510);
DISPLAY 0.723404 (-15760 2510);
WIRE 16 -1 (-12650 2875)(-11975 2875);
WIRE 16 -1 (-12650 2775)(-12650 2875);
FORCEPROP 2 LAST SIG_NAME HSC_VIN_UVW_N
J 0
(-12535 2885);
DISPLAY 0.723404 (-12535 2885);
FORCEPROP 2 LASTPROP $XRERR UNIQUE?
J 0
(-12775 2885);
DISPLAY 0.638298 (-12775 2885);
PAINT MONO (-12775 2885);
DISPLAY INVISIBLE (-12775 2885);
WIRE 16 -1 (-13000 2775)(-12650 2775);
WIRE 16 -1 (-13000 2650)(-12500 2650);
WIRE 16 -1 (-12500 2775)(-12500 2650);
WIRE 16 -1 (-11975 2775)(-12500 2775);
FORCEPROP 2 LAST SIG_NAME HSC_EN_R
J 0
(-12360 2785);
DISPLAY 0.723404 (-12360 2785);
FORCEPROP 2 LASTPROP $XRERR UNIQUE?
J 0
(-12600 2785);
DISPLAY 0.638298 (-12600 2785);
PAINT MONO (-12600 2785);
DISPLAY INVISIBLE (-12600 2785);
WIRE 16 -1 (-14525 2500)(-14225 2500);
WIRE 16 -1 (-13775 2500)(-14225 2500);
WIRE 16 -1 (-14225 2575)(-14225 2500);
WIRE 16 -1 (-13775 2975)(-13775 2500);
WIRE 16 -1 (-11975 2975)(-13775 2975);
FORCEPROP 2 LAST SIG_NAME IRQ_SML1_PMBUS_ALERT
J 0
(-12760 2985);
DISPLAY 0.723404 (-12760 2985);
FORCEPROP 2 LASTPROP $XRERR UNIQUE?
J 0
(-13000 2985);
DISPLAY 0.638298 (-13000 2985);
PAINT MONO (-13000 2985);
DISPLAY INVISIBLE (-13000 2985);
WIRE 16 -1 (-13000 2525)(-11975 2525);
FORCEPROP 2 LAST SIG_NAME HSC_ON_R
J 0
(-12360 2535);
DISPLAY 0.723404 (-12360 2535);
FORCEPROP 2 LASTPROP $XRERR UNIQUE?
J 0
(-12600 2535);
DISPLAY 0.638298 (-12600 2535);
PAINT MONO (-12600 2535);
DISPLAY INVISIBLE (-12600 2535);
WIRE 16 -1 (-14250 2300)(-13600 2300);
WIRE 16 -1 (-13600 2300)(-13600 2650);
WIRE 16 -1 (-13200 2650)(-13600 2650);
FORCEPROP 2 LAST SIG_NAME HSC_EN
J 0
(-14235 2310);
DISPLAY 0.723404 (-14235 2310);
WIRE 16 -1 (-13475 2525)(-13200 2525);
WIRE 16 -1 (-13475 2150)(-13475 2525);
WIRE 16 -1 (-14250 2150)(-13475 2150);
FORCEPROP 2 LAST SIG_NAME HSC_ON
J 0
(-14235 2160);
DISPLAY 0.723404 (-14235 2160);
WIRE 16 -1 (-11975 2375)(-12850 2375);
FORCEPROP 2 LAST SIG_NAME HSC_VDD18
J 0
(-12385 2385);
DISPLAY 0.723404 (-12385 2385);
FORCEPROP 2 LASTPROP $XRERR UNIQUE?
J 0
(-12625 2385);
DISPLAY 0.638298 (-12625 2385);
PAINT MONO (-12625 2385);
DISPLAY INVISIBLE (-12625 2385);
WIRE 16 -1 (-12850 2375)(-12850 2250);
WIRE 16 -1 (-12850 2375)(-13325 2375);
WIRE 16 -1 (-13325 2375)(-13325 2275);
WIRE 16 -1 (-12850 1850)(-12850 1950);
WIRE 16 -1 (-12850 2050)(-12850 1950);
WIRE 16 -1 (-12375 1950)(-12850 1950);
WIRE 16 -1 (-12375 1950)(-12375 2225);
FORCEPROP 2 LAST SIG_NAME HSC_ADDR
J 0
(-12360 2235);
DISPLAY 0.723404 (-12360 2235);
FORCEPROP 2 LASTPROP $XRERR UNIQUE?
J 0
(-12600 2235);
DISPLAY 0.638298 (-12600 2235);
PAINT MONO (-12600 2235);
DISPLAY INVISIBLE (-12600 2235);
WIRE 16 -1 (-12375 2225)(-11975 2225);
WIRE 16 -1 (-9975 3400)(-9050 3400);
WIRE 16 -1 (-9975 3275)(-9975 3400);
WIRE 16 -1 (-9850 3275)(-9975 3275);
WIRE 16 -1 (-10825 3275)(-9975 3275);
FORCEPROP 2 LAST SIG_NAME HSC_D_OC_R
J 0
(-10710 3285);
DISPLAY 0.808511 (-10710 3285);
WIRE 16 -1 (-8850 3575)(-8000 3575);
WIRE 16 -1 (-7425 3575)(-8000 3575);
FORCEPROP 2 LAST SIG_NAME IRQ_HSC_FAULT_N
J 0
(-7935 3585);
DISPLAY 0.723404 (-7935 3585);
WIRE 16 -1 (-8000 3800)(-8000 3575);
WIRE 16 -1 (-8850 3400)(-8425 3400);
WIRE 16 -1 (-8425 3400)(-7425 3400);
FORCEPROP 2 LAST SIG_NAME HSC_D_OC
J 0
(-7735 3410);
DISPLAY 0.808511 (-7735 3410);
WIRE 16 -1 (-8425 3800)(-8425 3400);
WIRE 16 -1 (-10100 3575)(-9050 3575);
WIRE 16 -1 (-10100 3475)(-10100 3575);
WIRE 16 -1 (-9850 3475)(-10100 3475);
WIRE 16 -1 (-10100 3375)(-10100 3475);
WIRE 16 -1 (-10825 3375)(-10100 3375);
FORCEPROP 2 LAST SIG_NAME HSC_FAULT
J 0
(-10710 3385);
DISPLAY 0.808511 (-10710 3385);
WIRE 16 -1 (-8525 3275)(-8225 3275);
WIRE 16 -1 (-8525 3175)(-8525 3275);
WIRE 16 -1 (-10825 3175)(-8525 3175);
FORCEPROP 2 LAST SIG_NAME HSC_MODE
J 0
(-10710 3185);
DISPLAY 0.808511 (-10710 3185);
FORCEPROP 2 LASTPROP $XRERR UNIQUE?
J 0
(-10950 3185);
DISPLAY 0.638298 (-10950 3185);
PAINT MONO (-10950 3185);
DISPLAY INVISIBLE (-10950 3185);
WIRE 16 -1 (-8350 2675)(-8450 2675);
WIRE 16 -1 (-8450 2675)(-8450 2550);
WIRE 16 -1 (-8925 2675)(-8450 2675);
WIRE 16 -1 (-8925 2525)(-8925 2675);
WIRE 16 -1 (-10825 2675)(-8925 2675);
FORCEPROP 2 LAST SIG_NAME HSC_VTEMP
J 0
(-10710 2685);
DISPLAY 0.808511 (-10710 2685);
WIRE 16 -1 (-9500 2375)(-9425 2375);
WIRE 16 -1 (-9500 2375)(-9500 2275);
WIRE 16 -1 (-10825 2375)(-9500 2375);
FORCEPROP 2 LAST SIG_NAME HSC_SS
J 0
(-10710 2385);
DISPLAY 0.808511 (-10710 2385);
WIRE 16 -1 (-10825 2975)(-10250 2975);
FORCEPROP 2 LAST SIG_NAME HSC_CS
J 0
(-10710 2985);
DISPLAY 0.808511 (-10710 2985);
FORCEPROP 2 LASTPROP $XRERR UNIQUE?
J 0
(-10950 2985);
DISPLAY 0.638298 (-10950 2985);
PAINT MONO (-10950 2985);
DISPLAY INVISIBLE (-10950 2985);
WIRE 16 -1 (-7425 3075)(-7625 3075);
WIRE 16 -1 (-7625 3075)(-8100 3075);
WIRE 16 -1 (-7625 3075)(-7625 2975);
WIRE 16 -1 (-8100 2950)(-8100 3075);
WIRE 16 -1 (-10825 3075)(-8100 3075);
FORCEPROP 2 LAST SIG_NAME HSC_IMON
J 0
(-10710 3085);
DISPLAY 0.808511 (-10710 3085);
WIRE 16 -1 (-14925 3450)(-14925 3500);
WIRE 16 -1 (-14925 3400)(-14925 3450);
WIRE 16 -1 (-15425 3450)(-14925 3450);
WIRE 16 -1 (-15425 3525)(-15425 3450);
WIRE 16 -1 (-13175 3800)(-13175 3675);
WIRE 16 -1 (-13175 3675)(-13700 3675);
WIRE 16 -1 (-13700 3675)(-13700 3800);
WIRE 16 -1 (-13700 3625)(-13700 3675);
WIRE 16 -1 (-13600 2775)(-13200 2775);
WIRE 16 -1 (-13600 2800)(-13600 2775);
WIRE 16 -1 (-11975 2075)(-12075 2075);
WIRE 16 -1 (-12075 2075)(-12075 2025);
WIRE 16 -1 (-11975 2025)(-12075 2025);
WIRE 16 -1 (-12075 2025)(-12075 1975);
WIRE 16 -1 (-8450 2350)(-8450 2225);
WIRE 16 -1 (-8450 2225)(-8625 2225);
WIRE 16 -1 (-8625 2150)(-8625 2225);
WIRE 16 -1 (-8925 2225)(-8625 2225);
WIRE 16 -1 (-8925 2225)(-8925 2325);
WIRE 16 -1 (-7625 2775)(-7625 2725);
WIRE 16 -1 (-7625 2650)(-7625 2725);
WIRE 16 -1 (-7625 2725)(-8100 2725);
WIRE 16 -1 (-8100 2725)(-8100 2750);
WIRE 16 -1 (-9225 3950)(-9225 3825);
WIRE 16 -1 (-9175 3825)(-9225 3825);
WIRE 16 -1 (-9125 3825)(-9175 3825);
WIRE 16 -1 (-9175 3775)(-9175 3825);
WIRE 16 -1 (-9125 3825)(-9125 3950);
WIRE 16 -1 (-8425 4000)(-8425 4125);
WIRE 16 -1 (-8425 4125)(-8225 4125);
WIRE 16 -1 (-8000 4125)(-8225 4125);
WIRE 16 -1 (-8225 4200)(-8225 4125);
WIRE 16 -1 (-8000 4125)(-8000 4000);
WIRE 16 -1 (-9975 1700)(-9525 1700);
WIRE 16 -1 (-9975 1700)(-9975 1800);
WIRE 16 -1 (-9975 1650)(-9975 1700);
WIRE 16 -1 (-9975 1550)(-9975 1650);
WIRE 16 -1 (-10325 1650)(-9975 1650);
WIRE 16 -1 (-10325 2075)(-10325 1650);
WIRE 16 -1 (-10825 2075)(-10325 2075);
FORCEPROP 2 LAST SIG_NAME MB0_P12V_STBY_PWRGD
J 0
(-10710 2085);
DISPLAY 0.723404 (-10710 2085);
WIRE 16 -1 (-12575 3575)(-11975 3575);
WIRE 16 -1 (-12575 4125)(-12575 3575);
WIRE 16 -1 (-13175 4125)(-12575 4125);
FORCEPROP 2 LAST SIG_NAME HSC_VSENSE
J 0
(-12460 3585);
DISPLAY 0.808511 (-12460 3585);
FORCEPROP 2 LASTPROP $XRERR UNIQUE?
J 0
(-12700 3585);
DISPLAY 0.638298 (-12700 3585);
PAINT MONO (-12700 3585);
DISPLAY INVISIBLE (-12700 3585);
WIRE 16 -1 (-13700 4125)(-13175 4125);
WIRE 16 -1 (-13175 4125)(-13175 4000);
WIRE 16 -1 (-13700 4125)(-13700 4250);
WIRE 16 -1 (-13700 4000)(-13700 4125);
WIRE 16 -1 (-9775 3875)(-9775 3775);
WIRE 16 -1 (-9775 3725)(-9775 3775);
WIRE 16 -1 (-9775 3775)(-10250 3775);
WIRE 16 -1 (-10250 3775)(-10250 3875);
WIRE 16 -1 (-8575 4750)(-8575 4650);
WIRE 16 -1 (-8575 4650)(-9175 4650);
WIRE 16 -1 (-9175 4650)(-9175 4500);
WIRE 16 -1 (-10325 4650)(-9175 4650);
WIRE 16 -1 (-10650 4650)(-10325 4650);
WIRE 16 -1 (-10325 4525)(-10325 4650);
WIRE 16 -1 (-10650 4125)(-10650 4650);
WIRE 16 -1 (-10650 4125)(-10675 4125);
WIRE 16 -1 (-10825 4125)(-10675 4125);
WIRE 16 -1 (-10675 4075)(-10675 4125);
WIRE 16 -1 (-10675 4025)(-10675 4075);
WIRE 16 -1 (-10825 4075)(-10675 4075);
WIRE 16 -1 (-10675 3975)(-10675 4025);
WIRE 16 -1 (-10825 4025)(-10675 4025);
WIRE 16 -1 (-10675 3925)(-10675 3975);
WIRE 16 -1 (-10825 3975)(-10675 3975);
WIRE 16 -1 (-10675 3875)(-10675 3925);
WIRE 16 -1 (-10825 3925)(-10675 3925);
WIRE 16 -1 (-10675 3825)(-10675 3875);
WIRE 16 -1 (-10825 3875)(-10675 3875);
WIRE 16 -1 (-10675 3775)(-10675 3825);
WIRE 16 -1 (-10825 3825)(-10675 3825);
WIRE 16 -1 (-10675 3725)(-10675 3775);
WIRE 16 -1 (-10825 3775)(-10675 3775);
WIRE 16 -1 (-10675 3675)(-10675 3725);
WIRE 16 -1 (-10825 3725)(-10675 3725);
WIRE 16 -1 (-10825 3675)(-10675 3675);
WIRE 16 -1 (-10825 3575)(-10350 3575);
WIRE 16 -1 (-10350 3575)(-10350 4200);
WIRE 16 -1 (-10350 4200)(-10325 4200);
WIRE 16 -1 (-10325 4200)(-10325 4325);
WIRE 16 -1 (-10325 4200)(-10250 4200);
WIRE 16 -1 (-9775 4200)(-10250 4200);
WIRE 16 -1 (-10250 4075)(-10250 4200);
WIRE 16 -1 (-9775 4200)(-9775 4075);
WIRE 16 -1 (-12125 4825)(-12125 4125);
WIRE 16 -1 (-12125 4825)(-13700 4825);
WIRE 16 -1 (-11975 4125)(-12125 4125);
WIRE 16 -1 (-12125 4125)(-12125 4075);
WIRE 16 -1 (-11975 4075)(-12125 4075);
WIRE 16 -1 (-12125 4075)(-12125 4025);
WIRE 16 -1 (-13700 4825)(-13700 4450);
WIRE 16 -1 (-14225 4825)(-13700 4825);
WIRE 16 -1 (-14225 4450)(-14225 4825);
WIRE 16 -1 (-14225 4825)(-14225 4925);
WIRE 16 -1 (-11975 4025)(-12125 4025);
WIRE 16 -1 (-12125 4025)(-12125 3975);
WIRE 16 -1 (-11975 3975)(-12125 3975);
WIRE 16 -1 (-12125 3975)(-12125 3925);
WIRE 16 -1 (-11975 3925)(-12125 3925);
WIRE 16 -1 (-12125 3925)(-12125 3875);
WIRE 16 -1 (-11975 3875)(-12125 3875);
WIRE 16 -1 (-12125 3875)(-12125 3825);
WIRE 16 -1 (-12125 3825)(-11975 3825);
WIRE 16 -1 (-12125 3825)(-12125 3775);
WIRE 16 -1 (-12125 3775)(-11975 3775);
WIRE 16 -1 (-12125 3775)(-12125 3725);
WIRE 16 -1 (-12125 3725)(-11975 3725);
WIRE 16 -1 (-12125 3725)(-12125 3675);
WIRE 16 -1 (-12125 3675)(-11975 3675);
DOT 1 (-9500 2375);
DOT 1 (-8925 2675);
DOT 1 (-8625 2225);
DOT 1 (-8225 4125);
DOT 1 (-9175 3825);
DOT 1 (-10250 4200);
DOT 1 (-10675 4075);
DOT 1 (-9175 4650);
DOT 1 (-14225 2500);
DOT 1 (-12125 3975);
DOT 1 (-12125 4025);
DOT 1 (-12850 1950);
DOT 1 (-10675 4125);
DOT 1 (-12850 2375);
DOT 1 (-8000 3575);
DOT 1 (-7625 3075);
DOT 1 (-7625 2725);
DOT 1 (-8425 3400);
DOT 1 (-8100 3075);
DOT 1 (-8450 2675);
DOT 1 (-9775 3775);
DOT 1 (-10325 4650);
DOT 1 (-10325 4200);
DOT 1 (-10675 3975);
DOT 1 (-10675 4025);
DOT 1 (-10675 3875);
DOT 1 (-10675 3775);
DOT 1 (-10675 3725);
DOT 1 (-9975 3275);
DOT 1 (-10100 3475);
DOT 1 (-9975 1650);
DOT 1 (-9975 1700);
DOT 1 (-12125 4075);
DOT 1 (-12125 3925);
DOT 1 (-12125 3875);
DOT 1 (-12125 3825);
DOT 1 (-12125 3725);
DOT 1 (-12225 3375);
DOT 1 (-12075 2025);
DOT 1 (-13700 4825);
DOT 1 (-14925 3875);
DOT 1 (-14925 3450);
DOT 1 (-14225 4825);
DOT 1 (-15225 3875);
DOT 1 (-10675 3925);
DOT 1 (-10675 3825);
DOT 1 (-13175 4125);
DOT 1 (-12125 3775);
DOT 1 (-13700 3675);
DOT 1 (-12125 4125);
DOT 1 (-13700 4125);
FORCENOTE
EN>1.2V ON
(-12475 2675) 0;
DISPLAY LEFT (-12475 2675);
DISPLAY 1.021277 (-12475 2675);
FORCENOTE
EN<0.95V OFF
(-12475 2600) 0;
DISPLAY LEFT (-12475 2600);
DISPLAY 1.021277 (-12475 2600);
FORCENOTE
ADDRESS: 0X40(8-BIT) / 0X20(7-BIT)
(-12225 1550) 0;
DISPLAY LEFT (-12225 1550);
DISPLAY 1.021277 (-12225 1550);
PAINT SKYBLUE (-12225 1550);
FORCENOTE
VOUT SLEW RATE: 2V/MS
(-9175 1784) 0;
DISPLAY LEFT (-9175 1784);
DISPLAY 1.021277 (-9175 1784);
FORCENOTE
SOFT START TIME=6MS.
(-9175 1850) 0;
DISPLAY LEFT (-9175 1850);
DISPLAY 1.021277 (-9175 1850);
FORCENOTE
OV =14.333V
(-16100 5350) 0;
DISPLAY LEFT (-16100 5350);
DISPLAY 1.021277 (-16100 5350);
FORCENOTE
UV =10.091V
(-16100 5300) 0;
DISPLAY LEFT (-16100 5300);
DISPLAY 1.021277 (-16100 5300);
FORCENOTE
LATCH OFF MODE
(-16100 5175) 0;
DISPLAY LEFT (-16100 5175);
DISPLAY 1.021277 (-16100 5175);
FORCENOTE
FPH=220A
(-15400 5434) 0;
DISPLAY LEFT (-15400 5434);
DISPLAY 1.595745 (-15400 5434);
FORCENOTE
HOT SWAT CIRCUIT
(-16121 5613) 0;
DISPLAY LEFT (-16121 5613);
DISPLAY 2.000000 (-16121 5613);
FORCENOTE
ADDRESS 0X20
(-16100 5241) 0;
DISPLAY LEFT (-16100 5241);
DISPLAY 1.021277 (-16100 5241);
FORCENOTE
OCW=220A
(-16125 5434) 0;
DISPLAY LEFT (-16125 5434);
DISPLAY 1.595745 (-16125 5434);
FORCENOTE
OCP=240A
(-16125 5509) 0;
DISPLAY LEFT (-16125 5509);
DISPLAY 1.595745 (-16125 5509);
QUIT
